G04*
G04 #@! TF.GenerationSoftware,Altium Limited,Altium Designer,23.0.1 (38)*
G04*
G04 Layer_Physical_Order=4*
G04 Layer_Color=6736896*
%FSLAX25Y25*%
%MOIN*%
G70*
G04*
G04 #@! TF.SameCoordinates,C48E81DB-6E20-4E2D-80E6-7C5AFAA1A21F*
G04*
G04*
G04 #@! TF.FilePolarity,Positive*
G04*
G01*
G75*
%ADD14C,0.01000*%
%ADD19C,0.00500*%
%ADD24C,0.00800*%
%ADD239R,0.06102X0.06102*%
%ADD241C,0.10000*%
%ADD248C,0.05906*%
%ADD250C,0.01600*%
G36*
X197835Y17717D02*
X304962D01*
X305082Y17217D01*
X304304Y16820D01*
X302903Y15802D01*
X301679Y14578D01*
X300661Y13177D01*
X299875Y11634D01*
X299340Y9988D01*
X299069Y8277D01*
Y6546D01*
X299340Y4836D01*
X299875Y3189D01*
X300661Y1647D01*
X301679Y246D01*
X302903Y-979D01*
X304304Y-1996D01*
X305846Y-2782D01*
X307493Y-3317D01*
X309203Y-3588D01*
X310935D01*
X312645Y-3317D01*
X314292Y-2782D01*
X315834Y-1996D01*
X317235Y-979D01*
X318459Y246D01*
X319477Y1647D01*
X320263Y3189D01*
X320798Y4836D01*
X321069Y6546D01*
Y8277D01*
X320798Y9988D01*
X320263Y11634D01*
X319477Y13177D01*
X318459Y14578D01*
X317235Y15802D01*
X315834Y16820D01*
X315055Y17217D01*
X315176Y17717D01*
X408559D01*
X408678Y17217D01*
X407591Y16662D01*
X406190Y15645D01*
X404966Y14420D01*
X403948Y13020D01*
X403162Y11477D01*
X402627Y9830D01*
X402356Y8120D01*
Y6389D01*
X402627Y4679D01*
X403162Y3032D01*
X403948Y1489D01*
X404966Y88D01*
X406190Y-1136D01*
X407591Y-2154D01*
X409134Y-2940D01*
X410780Y-3475D01*
X412491Y-3746D01*
X414222D01*
X415932Y-3475D01*
X417579Y-2940D01*
X419122Y-2154D01*
X420522Y-1136D01*
X421747Y88D01*
X422764Y1489D01*
X423550Y3032D01*
X424085Y4679D01*
X424356Y6389D01*
Y8120D01*
X424085Y9830D01*
X423550Y11477D01*
X422764Y13020D01*
X421747Y14420D01*
X420522Y15645D01*
X419122Y16662D01*
X418034Y17217D01*
X418154Y17717D01*
X546696D01*
X546830Y17217D01*
X546628Y17100D01*
X545892Y16364D01*
X545372Y15463D01*
X545102Y14457D01*
Y13417D01*
X545372Y12411D01*
X545892Y11510D01*
X546628Y10774D01*
X547529Y10254D01*
X548535Y9984D01*
X549576D01*
X550581Y10254D01*
X551482Y10774D01*
X552218Y11510D01*
X552739Y12411D01*
X553008Y13417D01*
Y14457D01*
X552739Y15463D01*
X552218Y16364D01*
X551482Y17100D01*
X551280Y17217D01*
X551414Y17717D01*
X556696D01*
X556830Y17217D01*
X556628Y17100D01*
X555892Y16364D01*
X555372Y15463D01*
X555102Y14457D01*
Y13417D01*
X555372Y12411D01*
X555892Y11510D01*
X556628Y10774D01*
X557529Y10254D01*
X558535Y9984D01*
X559576D01*
X560581Y10254D01*
X561482Y10774D01*
X562218Y11510D01*
X562739Y12411D01*
X563008Y13417D01*
Y14457D01*
X562739Y15463D01*
X562218Y16364D01*
X561482Y17100D01*
X561280Y17217D01*
X561414Y17717D01*
X566696D01*
X566830Y17217D01*
X566628Y17100D01*
X565892Y16364D01*
X565372Y15463D01*
X565102Y14457D01*
Y13417D01*
X565372Y12411D01*
X565892Y11510D01*
X566628Y10774D01*
X567529Y10254D01*
X568535Y9984D01*
X569576D01*
X570581Y10254D01*
X571482Y10774D01*
X572218Y11510D01*
X572739Y12411D01*
X573008Y13417D01*
Y14457D01*
X572739Y15463D01*
X572218Y16364D01*
X571482Y17100D01*
X571280Y17217D01*
X571414Y17717D01*
X576696D01*
X576830Y17217D01*
X576628Y17100D01*
X575892Y16364D01*
X575372Y15463D01*
X575102Y14457D01*
Y13417D01*
X575372Y12411D01*
X575892Y11510D01*
X576628Y10774D01*
X577529Y10254D01*
X578535Y9984D01*
X579575D01*
X580581Y10254D01*
X581482Y10774D01*
X582218Y11510D01*
X582738Y12411D01*
X583008Y13417D01*
Y14457D01*
X582738Y15463D01*
X582218Y16364D01*
X581482Y17100D01*
X581280Y17217D01*
X581414Y17717D01*
X585102D01*
Y9984D01*
X593008D01*
Y17717D01*
X617717D01*
X617717Y-13780D01*
X658236D01*
X658570Y-14279D01*
X658436Y-14603D01*
Y-15319D01*
X658710Y-15980D01*
X659217Y-16487D01*
X659878Y-16761D01*
X660594D01*
X661256Y-16487D01*
X661762Y-15980D01*
X662036Y-15319D01*
Y-14603D01*
X661902Y-14279D01*
X662236Y-13780D01*
X674016D01*
Y-27455D01*
X673600Y-27733D01*
X673586Y-27728D01*
X672870D01*
X672209Y-28002D01*
X671702Y-28508D01*
X671428Y-29169D01*
Y-29886D01*
X671702Y-30547D01*
X672209Y-31054D01*
X672870Y-31328D01*
X673586D01*
X673600Y-31322D01*
X674016Y-31600D01*
Y-41365D01*
X673953Y-41416D01*
X673454Y-41180D01*
Y-40980D01*
X673179Y-40319D01*
X672673Y-39813D01*
X672012Y-39539D01*
X671295D01*
X670634Y-39813D01*
X670128Y-40319D01*
X669853Y-40980D01*
Y-41697D01*
X670128Y-42358D01*
X670634Y-42865D01*
X671295Y-43139D01*
X672012D01*
X672673Y-42865D01*
X673179Y-42358D01*
X673283Y-42109D01*
X673358Y-42009D01*
X673791Y-42162D01*
X673791Y-42329D01*
Y-42878D01*
X674016Y-43421D01*
Y-110630D01*
X692913D01*
Y-172047D01*
X688421D01*
X688343Y-171657D01*
X688123Y-171326D01*
X687792Y-171105D01*
X687402Y-171028D01*
X678989D01*
X678891Y-171047D01*
X678790Y-171047D01*
X678697Y-171086D01*
X678599Y-171105D01*
X678515Y-171161D01*
X678456Y-171186D01*
X678185Y-170915D01*
X677523Y-170641D01*
X676807D01*
X676146Y-170915D01*
X675639Y-171421D01*
X675467Y-171838D01*
X674927D01*
X674754Y-171421D01*
X674248Y-170915D01*
X673586Y-170641D01*
X672870D01*
X672209Y-170915D01*
X671938Y-171186D01*
X671878Y-171161D01*
X671795Y-171105D01*
X671696Y-171086D01*
X671603Y-171047D01*
X671503Y-171047D01*
X671405Y-171028D01*
X650000D01*
Y-155118D01*
Y-149213D01*
Y-145150D01*
X650114Y-144577D01*
Y-143313D01*
X650000Y-142739D01*
Y-133858D01*
X650114D01*
Y-121031D01*
X650000D01*
Y-119291D01*
X622441D01*
Y-101111D01*
X622485Y-101067D01*
X622759Y-100405D01*
Y-99689D01*
X622485Y-99028D01*
X622441Y-98984D01*
Y-83858D01*
X620430D01*
X620368Y-83358D01*
X620424Y-83303D01*
X620698Y-82642D01*
Y-81925D01*
X620424Y-81264D01*
X619917Y-80757D01*
X619256Y-80484D01*
X618540D01*
X617878Y-80757D01*
X617372Y-81264D01*
X617098Y-81925D01*
Y-82389D01*
X616957Y-82705D01*
X616641Y-82846D01*
X616177D01*
X615516Y-83120D01*
X615009Y-83626D01*
X614995Y-83661D01*
X614913Y-83858D01*
X614735Y-84288D01*
Y-85004D01*
X615009Y-85665D01*
X615516Y-86172D01*
X616177Y-86446D01*
X616893D01*
X617055Y-86379D01*
X617470Y-86657D01*
Y-93503D01*
X613951Y-97022D01*
X613642Y-97485D01*
X613558Y-97908D01*
X613108Y-98263D01*
X612956Y-98200D01*
X612240D01*
X611579Y-98474D01*
X611072Y-98980D01*
X610798Y-99642D01*
Y-100358D01*
X611072Y-101020D01*
X611579Y-101526D01*
X612240Y-101800D01*
X612956D01*
X613118Y-101733D01*
X613533Y-102011D01*
Y-110432D01*
X584587Y-139379D01*
X584091Y-139168D01*
Y-122835D01*
X584013Y-122444D01*
X583792Y-122114D01*
X583461Y-121893D01*
X583071Y-121815D01*
X564405D01*
Y-78579D01*
X577467D01*
X577567Y-79079D01*
X577148Y-79252D01*
X576642Y-79759D01*
X576368Y-80420D01*
Y-81136D01*
X576642Y-81798D01*
X576973Y-82130D01*
X576933Y-82332D01*
X576427Y-82839D01*
X576153Y-83500D01*
Y-84216D01*
X576427Y-84878D01*
X576933Y-85384D01*
X577595Y-85658D01*
X578311D01*
X578972Y-85384D01*
X579479Y-84878D01*
X579753Y-84216D01*
Y-83500D01*
X579479Y-82839D01*
X579147Y-82507D01*
X579187Y-82304D01*
X579694Y-81798D01*
X579968Y-81136D01*
Y-80420D01*
X579694Y-79759D01*
X579187Y-79252D01*
X578768Y-79079D01*
X578868Y-78579D01*
X586614D01*
X587004Y-78501D01*
X587335Y-78280D01*
X587556Y-77949D01*
X587634Y-77559D01*
Y-59055D01*
X587556Y-58665D01*
X587335Y-58334D01*
X587004Y-58113D01*
X586614Y-58035D01*
X550000D01*
X549610Y-58113D01*
X549279Y-58334D01*
X549058Y-58665D01*
X548980Y-59055D01*
Y-138774D01*
X548480Y-138981D01*
X546679Y-137180D01*
X546215Y-136870D01*
X545669Y-136761D01*
X545669Y-136762D01*
X526421D01*
X526143Y-136346D01*
X526209Y-136185D01*
Y-135469D01*
X525935Y-134807D01*
X525429Y-134301D01*
X524767Y-134027D01*
X524051D01*
X523390Y-134301D01*
X522884Y-134807D01*
X522610Y-135469D01*
Y-136185D01*
X522676Y-136346D01*
X522398Y-136762D01*
X521260D01*
X520714Y-136870D01*
X520251Y-137180D01*
X520251Y-137180D01*
X517666Y-139764D01*
X470834Y-139764D01*
X470493Y-139378D01*
X470540Y-139141D01*
X471047Y-138634D01*
X471321Y-137973D01*
Y-137257D01*
X471047Y-136595D01*
X470540Y-136089D01*
X469879Y-135815D01*
X469163D01*
X468501Y-136089D01*
X467995Y-136595D01*
X467666Y-136661D01*
X437033Y-106028D01*
X436570Y-105718D01*
X436530Y-105201D01*
X436846Y-105069D01*
X437353Y-104563D01*
X437627Y-103901D01*
Y-103185D01*
X437353Y-102524D01*
X436846Y-102017D01*
X436185Y-101743D01*
X435469D01*
X434807Y-102017D01*
X434301Y-102524D01*
X434027Y-103185D01*
Y-103901D01*
X434301Y-104563D01*
X434807Y-105069D01*
X434904Y-105110D01*
X434805Y-105610D01*
X418076D01*
X417956Y-105110D01*
X419122Y-104516D01*
X420522Y-103498D01*
X421747Y-102274D01*
X422764Y-100873D01*
X423550Y-99330D01*
X424085Y-97684D01*
X424356Y-95973D01*
Y-94242D01*
X424085Y-92532D01*
X423550Y-90885D01*
X422764Y-89343D01*
X421747Y-87942D01*
X420522Y-86717D01*
X419122Y-85700D01*
X417579Y-84914D01*
X415932Y-84379D01*
X414222Y-84108D01*
X412491D01*
X410780Y-84379D01*
X409134Y-84914D01*
X407591Y-85700D01*
X406190Y-86717D01*
X404966Y-87942D01*
X403948Y-89343D01*
X403162Y-90885D01*
X402627Y-92532D01*
X402356Y-94242D01*
Y-95973D01*
X402627Y-97684D01*
X403162Y-99330D01*
X403948Y-100873D01*
X404966Y-102274D01*
X406190Y-103498D01*
X407591Y-104516D01*
X408756Y-105110D01*
X408636Y-105610D01*
X398811D01*
X389042Y-95841D01*
X388579Y-95532D01*
X388033Y-95423D01*
X388033Y-95423D01*
X367266D01*
X367266Y-95423D01*
X366720Y-95532D01*
X366256Y-95841D01*
X366256Y-95841D01*
X356488Y-105610D01*
X314690D01*
X314637Y-105530D01*
X314807Y-104882D01*
X315834Y-104358D01*
X317235Y-103341D01*
X318459Y-102117D01*
X319477Y-100716D01*
X320263Y-99173D01*
X320798Y-97526D01*
X321069Y-95816D01*
Y-94085D01*
X320798Y-92375D01*
X320263Y-90728D01*
X319477Y-89185D01*
X318459Y-87784D01*
X317235Y-86560D01*
X315834Y-85542D01*
X314292Y-84756D01*
X312645Y-84221D01*
X310935Y-83951D01*
X309203D01*
X307493Y-84221D01*
X305846Y-84756D01*
X304304Y-85542D01*
X302903Y-86560D01*
X301679Y-87784D01*
X300661Y-89185D01*
X299875Y-90728D01*
X299340Y-92375D01*
X299069Y-94085D01*
Y-95816D01*
X299340Y-97526D01*
X299875Y-99173D01*
X300661Y-100716D01*
X301679Y-102117D01*
X302903Y-103341D01*
X304304Y-104358D01*
X305331Y-104882D01*
X305501Y-105530D01*
X305448Y-105610D01*
X291438D01*
X269907Y-84079D01*
X269444Y-83769D01*
X268898Y-83661D01*
X268898Y-83661D01*
X116117D01*
X115973Y-83446D01*
Y-82730D01*
X115699Y-82069D01*
X115193Y-81562D01*
X114531Y-81288D01*
X113815D01*
X113154Y-81562D01*
X112647Y-82069D01*
X112373Y-82730D01*
Y-83446D01*
X112230Y-83661D01*
X89764D01*
X67372Y-61269D01*
Y-59041D01*
X67471Y-58943D01*
X67745Y-58281D01*
Y-57565D01*
X67471Y-56903D01*
X66965Y-56397D01*
X66303Y-56123D01*
X65587D01*
X64925Y-56397D01*
X64419Y-56903D01*
X64145Y-57565D01*
Y-58281D01*
X64419Y-58943D01*
X64517Y-59041D01*
Y-61860D01*
X64517Y-61860D01*
X64626Y-62406D01*
X64936Y-62869D01*
X65601Y-63535D01*
X65424Y-64064D01*
X64925Y-64271D01*
X64419Y-64777D01*
X64145Y-65439D01*
Y-66155D01*
X64419Y-66817D01*
X64925Y-67323D01*
X65587Y-67597D01*
X65726D01*
X85802Y-87672D01*
X85802Y-87672D01*
X86265Y-87982D01*
X86811Y-88090D01*
X267421D01*
X289148Y-109818D01*
X289148Y-109818D01*
X289611Y-110127D01*
X290158Y-110236D01*
X290158Y-110236D01*
X363902D01*
X363902Y-110236D01*
X364448Y-110127D01*
X364912Y-109818D01*
X372121Y-102609D01*
X387204D01*
X393350Y-108755D01*
X393159Y-109217D01*
X384981D01*
X384774Y-108717D01*
X384991Y-108500D01*
X385265Y-107838D01*
Y-107122D01*
X384991Y-106461D01*
X384484Y-105954D01*
X383823Y-105680D01*
X383106D01*
X382445Y-105954D01*
X382308Y-106091D01*
X381865Y-106301D01*
X381655Y-106091D01*
X381358Y-105795D01*
X380697Y-105521D01*
X379981D01*
X379319Y-105795D01*
X379097Y-106017D01*
X378732Y-106239D01*
X378444Y-106017D01*
X378185Y-105757D01*
X377523Y-105483D01*
X376807D01*
X376146Y-105757D01*
X375639Y-106264D01*
X375365Y-106925D01*
Y-107641D01*
X375639Y-108303D01*
X376053Y-108717D01*
X375939Y-109152D01*
X375900Y-109217D01*
X370472D01*
X370082Y-109294D01*
X369752Y-109515D01*
X369531Y-109846D01*
X369453Y-110236D01*
Y-128347D01*
X369531Y-128737D01*
X369260Y-129232D01*
X310959D01*
X310816Y-129017D01*
Y-128301D01*
X310542Y-127639D01*
X310035Y-127133D01*
X309374Y-126859D01*
X308658D01*
X307996Y-127133D01*
X307490Y-127639D01*
X307216Y-128301D01*
Y-129017D01*
X307072Y-129232D01*
X275690D01*
X274262Y-127804D01*
Y-124016D01*
X274262Y-124016D01*
X274153Y-123469D01*
X273844Y-123006D01*
X273844Y-123006D01*
X273453Y-122616D01*
Y-122477D01*
X273180Y-121815D01*
X272673Y-121309D01*
X272012Y-121035D01*
X271295D01*
X270634Y-121309D01*
X270128Y-121815D01*
X269853Y-122477D01*
Y-122771D01*
X269354Y-122871D01*
X269243Y-122602D01*
X268736Y-122096D01*
X268075Y-121822D01*
X267358D01*
X266697Y-122096D01*
X266191Y-122602D01*
X265916Y-123264D01*
Y-123980D01*
X266191Y-124642D01*
X266697Y-125148D01*
X267358Y-125422D01*
X268075D01*
X268736Y-125148D01*
X269243Y-124642D01*
X269516Y-123980D01*
Y-123686D01*
X270017Y-123586D01*
X270128Y-123854D01*
X270634Y-124361D01*
X271295Y-124635D01*
X271407D01*
Y-128395D01*
X271407Y-128395D01*
X271516Y-128942D01*
X271687Y-129197D01*
X271687Y-129304D01*
X271544Y-129719D01*
X271492Y-129778D01*
X271028Y-129970D01*
X270521Y-130476D01*
X270247Y-131138D01*
Y-131854D01*
X270521Y-132516D01*
X271028Y-133022D01*
X271689Y-133296D01*
X272405D01*
X273067Y-133022D01*
X273573Y-132516D01*
X273772Y-132037D01*
X273780Y-132027D01*
X274238Y-131844D01*
X274347Y-131841D01*
X274552Y-131978D01*
X275098Y-132087D01*
X275098Y-132087D01*
X279415D01*
X279606Y-132548D01*
X276574Y-135580D01*
X260827D01*
X253253Y-128006D01*
X253292Y-127776D01*
X253847Y-127476D01*
X254018Y-127547D01*
X254734D01*
X255395Y-127272D01*
X255902Y-126766D01*
X256176Y-126104D01*
Y-125388D01*
X255902Y-124727D01*
X255395Y-124221D01*
X254734Y-123946D01*
X254018D01*
X253502Y-124160D01*
X253002Y-123921D01*
Y-122638D01*
X253485Y-122156D01*
X253870Y-122233D01*
X254027Y-122321D01*
X254492Y-122786D01*
X255154Y-123060D01*
X255870D01*
X256531Y-122786D01*
X257038Y-122280D01*
X257312Y-121618D01*
Y-120902D01*
X257038Y-120240D01*
X256531Y-119734D01*
X256619Y-119549D01*
X256644Y-119524D01*
X256918Y-118862D01*
Y-118146D01*
X256644Y-117484D01*
X256138Y-116978D01*
X255476Y-116704D01*
X254760D01*
X254099Y-116978D01*
X253592Y-117484D01*
X253318Y-118146D01*
Y-118285D01*
X250566Y-121038D01*
X250256Y-121501D01*
X250147Y-122047D01*
X250147Y-122047D01*
Y-127603D01*
X249647Y-127810D01*
X249445Y-127608D01*
X248783Y-127334D01*
X248067D01*
X247406Y-127608D01*
X246899Y-128114D01*
X246625Y-128776D01*
Y-129492D01*
X246899Y-130154D01*
X247406Y-130660D01*
X248067Y-130934D01*
X248783D01*
X249445Y-130660D01*
X249951Y-130154D01*
X250163Y-129642D01*
X250215Y-129606D01*
X250588Y-129504D01*
X250718Y-129509D01*
X259227Y-138017D01*
X259227Y-138017D01*
X259690Y-138327D01*
X260236Y-138435D01*
X277165D01*
X277165Y-138435D01*
X277712Y-138327D01*
X278175Y-138017D01*
X282723Y-133469D01*
X412209D01*
X413920Y-135180D01*
X413802Y-135770D01*
X413547Y-135876D01*
X413041Y-136382D01*
X412767Y-137043D01*
Y-137760D01*
X413041Y-138421D01*
X413547Y-138927D01*
X414209Y-139202D01*
X414925D01*
X415587Y-138927D01*
X416093Y-138421D01*
X416199Y-138166D01*
X416788Y-138049D01*
X418041Y-139302D01*
X417850Y-139764D01*
X329657Y-139764D01*
X248475Y-139764D01*
X236860Y-128149D01*
Y-119489D01*
X238408Y-117942D01*
X238547D01*
X239027Y-117743D01*
X239414Y-118116D01*
X239277Y-118446D01*
Y-119162D01*
X239551Y-119824D01*
X240057Y-120330D01*
X240719Y-120605D01*
X241435D01*
X242096Y-120330D01*
X242603Y-119824D01*
X242877Y-119162D01*
Y-118446D01*
X242603Y-117785D01*
X242096Y-117279D01*
X241435Y-117005D01*
X240719D01*
X240239Y-117203D01*
X239852Y-116830D01*
X239989Y-116500D01*
Y-115784D01*
X239715Y-115122D01*
X239209Y-114616D01*
X238547Y-114342D01*
X237831D01*
X237169Y-114616D01*
X236663Y-115122D01*
X236389Y-115784D01*
Y-115923D01*
X234424Y-117888D01*
X234114Y-118351D01*
X234006Y-118898D01*
X234006Y-118898D01*
Y-128740D01*
X234006Y-128740D01*
X234114Y-129286D01*
X234424Y-129750D01*
X243976Y-139302D01*
X243785Y-139764D01*
X184055Y-139764D01*
Y-135827D01*
X122047D01*
Y-161171D01*
X88117D01*
X88117Y-161171D01*
X87571Y-161280D01*
X87108Y-161589D01*
X87108Y-161589D01*
X82455Y-166242D01*
X82146Y-166705D01*
X82037Y-167251D01*
X82037Y-167251D01*
Y-178248D01*
X81537Y-178513D01*
X81067Y-178318D01*
X80351D01*
X79689Y-178592D01*
X79183Y-179098D01*
X78909Y-179760D01*
Y-180476D01*
X79183Y-181138D01*
X79689Y-181644D01*
X80351Y-181918D01*
X81067D01*
X81537Y-181723D01*
X82037Y-181989D01*
Y-203909D01*
X81335D01*
X80673Y-204183D01*
X80167Y-204689D01*
X79893Y-205351D01*
Y-206067D01*
X80167Y-206728D01*
X80673Y-207235D01*
X81335Y-207509D01*
X82037D01*
Y-211616D01*
X82037Y-211616D01*
X82146Y-212163D01*
X82455Y-212626D01*
X83872Y-214043D01*
X84104Y-214602D01*
X84610Y-215109D01*
X85272Y-215383D01*
X85988D01*
X86650Y-215109D01*
X87156Y-214602D01*
X87430Y-213941D01*
Y-213225D01*
X87410Y-213176D01*
X87582Y-212709D01*
X87587Y-212703D01*
X87715Y-212630D01*
X88177Y-212821D01*
Y-219766D01*
X87677Y-219973D01*
X87634Y-219931D01*
X86972Y-219657D01*
X86256D01*
X85595Y-219931D01*
X85088Y-220437D01*
X84814Y-221099D01*
Y-221815D01*
X85088Y-222476D01*
X85595Y-222983D01*
X86256Y-223257D01*
X86972D01*
X87634Y-222983D01*
X87677Y-222940D01*
X88177Y-223147D01*
Y-257168D01*
X87677Y-257375D01*
X87634Y-257332D01*
X86972Y-257058D01*
X86256D01*
X85595Y-257332D01*
X85088Y-257839D01*
X84814Y-258500D01*
Y-259216D01*
X85088Y-259878D01*
X85595Y-260384D01*
X86093Y-260591D01*
X86270Y-261120D01*
X85411Y-261980D01*
X85272D01*
X84610Y-262254D01*
X84104Y-262760D01*
X83830Y-263422D01*
Y-264138D01*
X84104Y-264799D01*
X84284Y-264980D01*
X84104Y-265160D01*
X83830Y-265822D01*
Y-266538D01*
X84104Y-267199D01*
X84610Y-267705D01*
X85272Y-267980D01*
X85988D01*
X86650Y-267705D01*
X87156Y-267199D01*
X87271Y-266920D01*
X87468Y-266789D01*
X90315Y-263942D01*
X90776Y-264133D01*
Y-310320D01*
X87827Y-313269D01*
X87237Y-313152D01*
X87156Y-312957D01*
X86650Y-312450D01*
X85988Y-312176D01*
X85272D01*
X85107Y-312245D01*
X84607Y-311911D01*
Y-303982D01*
X85655Y-302934D01*
X85964Y-302471D01*
X86073Y-301924D01*
X86073Y-301924D01*
Y-279135D01*
X87817Y-277391D01*
X87957D01*
X88618Y-277116D01*
X89124Y-276610D01*
X89398Y-275949D01*
Y-275233D01*
X89124Y-274571D01*
X88618Y-274065D01*
X87957Y-273791D01*
X87240D01*
X86579Y-274065D01*
X86072Y-274571D01*
X85798Y-275233D01*
Y-275372D01*
X83636Y-277534D01*
X83327Y-277997D01*
X83218Y-278543D01*
X83218Y-278543D01*
Y-285722D01*
X82718Y-285981D01*
X82238Y-285782D01*
X81522D01*
X80860Y-286056D01*
X80354Y-286563D01*
X80080Y-287224D01*
Y-287940D01*
X80354Y-288602D01*
X80452Y-288701D01*
Y-324990D01*
X80452Y-324990D01*
X80561Y-325536D01*
X80870Y-325999D01*
X82652Y-327781D01*
X82652Y-327781D01*
X83115Y-328090D01*
X83661Y-328199D01*
X83662Y-328199D01*
X85925D01*
X86116Y-328661D01*
X86072Y-328705D01*
X85798Y-329366D01*
Y-330083D01*
X86072Y-330744D01*
X86579Y-331250D01*
X87240Y-331524D01*
X87957D01*
X88610Y-331254D01*
X101378D01*
X101963Y-331137D01*
X102459Y-330806D01*
X116183Y-317082D01*
X116414Y-317119D01*
X116683Y-317262D01*
Y-318306D01*
X95865Y-339124D01*
X79858D01*
X79760Y-339025D01*
X79098Y-338751D01*
X78382D01*
X77720Y-339025D01*
X77214Y-339532D01*
X76940Y-340193D01*
Y-340909D01*
X77214Y-341571D01*
X77720Y-342077D01*
X78382Y-342351D01*
X79098D01*
X79760Y-342077D01*
X79858Y-341979D01*
X96457D01*
X96457Y-341979D01*
X97003Y-341870D01*
X97466Y-341561D01*
X119120Y-319907D01*
X119120Y-319907D01*
X119429Y-319444D01*
X119538Y-318898D01*
Y-265308D01*
X119721Y-265186D01*
X120437D01*
X121098Y-264912D01*
X121547Y-264463D01*
X121818Y-264507D01*
X122047Y-264616D01*
Y-360236D01*
X58268D01*
Y-135827D01*
X25591D01*
Y-11015D01*
X26006Y-10737D01*
X26137Y-10791D01*
X26853D01*
X27515Y-10517D01*
X28021Y-10011D01*
X28295Y-9349D01*
Y-8633D01*
X28021Y-7972D01*
X27515Y-7465D01*
X26853Y-7191D01*
X26137D01*
X26006Y-7246D01*
X25591Y-6968D01*
Y17865D01*
X67064D01*
X67184Y17365D01*
X66115Y16820D01*
X64714Y15802D01*
X63490Y14578D01*
X62472Y13177D01*
X61686Y11634D01*
X61151Y9988D01*
X60880Y8277D01*
Y6546D01*
X61151Y4836D01*
X61686Y3189D01*
X62472Y1647D01*
X63490Y246D01*
X64714Y-979D01*
X66115Y-1996D01*
X67657Y-2782D01*
X69304Y-3317D01*
X71014Y-3588D01*
X72746D01*
X74456Y-3317D01*
X76103Y-2782D01*
X77645Y-1996D01*
X79046Y-979D01*
X80270Y246D01*
X81288Y1647D01*
X82074Y3189D01*
X82609Y4836D01*
X82880Y6546D01*
Y8277D01*
X82609Y9988D01*
X82074Y11634D01*
X81288Y13177D01*
X80270Y14578D01*
X79046Y15802D01*
X77645Y16820D01*
X76576Y17365D01*
X76696Y17865D01*
X197835D01*
Y17717D01*
D02*
G37*
G36*
X467491Y-144067D02*
Y-144206D01*
X467765Y-144868D01*
X468272Y-145374D01*
X468898Y-145633D01*
Y-158918D01*
X468519Y-159297D01*
X468202Y-160062D01*
Y-160891D01*
X468519Y-161656D01*
X468898Y-162036D01*
Y-173403D01*
X468370Y-173621D01*
X467864Y-174128D01*
X467590Y-174789D01*
Y-175505D01*
X467864Y-176167D01*
X468370Y-176673D01*
X468898Y-176892D01*
Y-181102D01*
X498207D01*
X498753Y-181328D01*
X499469D01*
X500014Y-181102D01*
X502362D01*
Y-161861D01*
X519455Y-144769D01*
X544882D01*
Y-147638D01*
X551085D01*
X552094Y-148647D01*
X552094Y-148647D01*
X552557Y-148957D01*
X553103Y-149065D01*
X553103Y-149065D01*
X581102D01*
X581102Y-149065D01*
X581649Y-148957D01*
X582112Y-148647D01*
X583121Y-147638D01*
X612598D01*
Y-172047D01*
X643586D01*
X644130Y-172272D01*
X644846D01*
X645390Y-172047D01*
X671405D01*
X671428Y-172083D01*
Y-172799D01*
X671702Y-173461D01*
X672209Y-173967D01*
X672870Y-174241D01*
X673586D01*
X674248Y-173967D01*
X674754Y-173461D01*
X674926Y-173046D01*
X675467D01*
X675639Y-173461D01*
X676146Y-173967D01*
X676807Y-174241D01*
X677523D01*
X678185Y-173967D01*
X678691Y-173461D01*
X678965Y-172799D01*
Y-172083D01*
X678989Y-172047D01*
X687402D01*
Y-205512D01*
X631940D01*
X615640Y-189212D01*
X615177Y-188903D01*
X614631Y-188794D01*
X614631Y-188794D01*
X566010D01*
X549194Y-171978D01*
X548731Y-171669D01*
X548184Y-171560D01*
X548184Y-171560D01*
X531145D01*
X531047Y-171462D01*
X530385Y-171187D01*
X529669D01*
X529007Y-171462D01*
X528501Y-171968D01*
X528227Y-172629D01*
Y-173346D01*
X528042Y-173622D01*
X527953D01*
Y-181102D01*
X546063D01*
Y-201785D01*
X545718Y-202130D01*
X545444Y-202792D01*
Y-203508D01*
X545718Y-204169D01*
X546063Y-204514D01*
Y-209449D01*
X443701D01*
Y-176849D01*
X444256D01*
X444917Y-176575D01*
X445424Y-176068D01*
X445698Y-175407D01*
Y-174691D01*
X445424Y-174029D01*
X444917Y-173523D01*
X444256Y-173249D01*
X444116D01*
X443701Y-172833D01*
Y-156693D01*
X443553D01*
Y-156151D01*
X443445Y-155605D01*
X443135Y-155142D01*
X443135Y-155142D01*
X417643Y-129650D01*
X417180Y-129340D01*
X416634Y-129232D01*
X416634Y-129232D01*
X412598D01*
Y-128347D01*
X370472D01*
Y-110236D01*
X401772D01*
X401871Y-110736D01*
X401699Y-110808D01*
X401193Y-111314D01*
X400919Y-111976D01*
Y-112692D01*
X401193Y-113353D01*
X401699Y-113859D01*
X402360Y-114134D01*
X403077D01*
X403738Y-113859D01*
X404245Y-113353D01*
X404519Y-112692D01*
Y-111976D01*
X404245Y-111314D01*
X403738Y-110808D01*
X403566Y-110736D01*
X403665Y-110236D01*
X433661D01*
X467491Y-144067D01*
D02*
G37*
G36*
X586614Y-77559D02*
X563386D01*
Y-122835D01*
X583071D01*
Y-139370D01*
X550000D01*
Y-59055D01*
X586614D01*
Y-77559D01*
D02*
G37*
G36*
X89209Y-168170D02*
X89349D01*
X102682Y-181503D01*
X102682Y-181503D01*
X103145Y-181813D01*
X103691Y-181921D01*
X122047D01*
Y-184949D01*
X106597D01*
X106597Y-184949D01*
X106050Y-185058D01*
X105587Y-185367D01*
X105587Y-185367D01*
X85553Y-205401D01*
X85392Y-205642D01*
X84892Y-205490D01*
Y-170839D01*
X85392Y-170632D01*
X85543Y-170783D01*
X86204Y-171057D01*
X86920D01*
X87582Y-170783D01*
X88088Y-170277D01*
X88362Y-169615D01*
Y-168899D01*
X88201Y-168510D01*
X88484Y-167980D01*
X88625Y-167928D01*
X89209Y-168170D01*
D02*
G37*
G36*
X122047Y-209534D02*
X120732D01*
X120732Y-209534D01*
X120185Y-209643D01*
X119722Y-209952D01*
X119722Y-209952D01*
X110211Y-219463D01*
X109902Y-219926D01*
X109793Y-220472D01*
X109793Y-220473D01*
Y-310432D01*
X96850Y-323376D01*
X85237D01*
X84694Y-322833D01*
X84729Y-322320D01*
X85137Y-322058D01*
X85272Y-322113D01*
X85988D01*
X86650Y-321839D01*
X87156Y-321333D01*
X87430Y-320671D01*
Y-320532D01*
X94513Y-313449D01*
X94513Y-313449D01*
X94823Y-312986D01*
X94931Y-312439D01*
X94931Y-312439D01*
Y-220202D01*
X95431Y-220103D01*
X95599Y-220508D01*
X96106Y-221014D01*
X96767Y-221288D01*
X97483D01*
X98145Y-221014D01*
X98651Y-220508D01*
X98925Y-219846D01*
Y-219130D01*
X98772Y-218761D01*
X98899Y-218567D01*
X99137Y-218335D01*
X99768D01*
X100429Y-218061D01*
X100935Y-217555D01*
X101209Y-216894D01*
Y-216367D01*
X101736D01*
X102398Y-216093D01*
X102904Y-215586D01*
X103178Y-214925D01*
Y-214209D01*
X103020Y-213827D01*
X102929Y-213525D01*
X103270Y-213224D01*
X103547Y-213109D01*
X104053Y-212602D01*
X104328Y-211941D01*
Y-211225D01*
X104169Y-210842D01*
X110110Y-204901D01*
X122047D01*
Y-209534D01*
D02*
G37*
G36*
X603150Y-246457D02*
X598032D01*
Y-268898D01*
X574803D01*
Y-259449D01*
Y-253937D01*
X559842D01*
Y-203150D01*
X585433D01*
Y-196457D01*
X603150D01*
Y-246457D01*
D02*
G37*
%LPC*%
G36*
X589575Y7890D02*
X588535D01*
X587529Y7620D01*
X586628Y7100D01*
X585892Y6364D01*
X585372Y5463D01*
X585102Y4457D01*
Y3417D01*
X585372Y2411D01*
X585892Y1510D01*
X586628Y774D01*
X587529Y254D01*
X588535Y-16D01*
X589575D01*
X590581Y254D01*
X591482Y774D01*
X592218Y1510D01*
X592738Y2411D01*
X593008Y3417D01*
Y4457D01*
X592738Y5463D01*
X592218Y6364D01*
X591482Y7100D01*
X590581Y7620D01*
X589575Y7890D01*
D02*
G37*
G36*
X579575D02*
X578535D01*
X577529Y7620D01*
X576628Y7100D01*
X575892Y6364D01*
X575372Y5463D01*
X575102Y4457D01*
Y3417D01*
X575372Y2411D01*
X575892Y1510D01*
X576628Y774D01*
X577529Y254D01*
X578535Y-16D01*
X579575D01*
X580581Y254D01*
X581482Y774D01*
X582218Y1510D01*
X582738Y2411D01*
X583008Y3417D01*
Y4457D01*
X582738Y5463D01*
X582218Y6364D01*
X581482Y7100D01*
X580581Y7620D01*
X579575Y7890D01*
D02*
G37*
G36*
X569576D02*
X568535D01*
X567529Y7620D01*
X566628Y7100D01*
X565892Y6364D01*
X565372Y5463D01*
X565102Y4457D01*
Y3417D01*
X565372Y2411D01*
X565892Y1510D01*
X566628Y774D01*
X567529Y254D01*
X568535Y-16D01*
X569576D01*
X570581Y254D01*
X571482Y774D01*
X572218Y1510D01*
X572739Y2411D01*
X573008Y3417D01*
Y4457D01*
X572739Y5463D01*
X572218Y6364D01*
X571482Y7100D01*
X570581Y7620D01*
X569576Y7890D01*
D02*
G37*
G36*
X559576D02*
X558535D01*
X557529Y7620D01*
X556628Y7100D01*
X555892Y6364D01*
X555372Y5463D01*
X555102Y4457D01*
Y3417D01*
X555372Y2411D01*
X555892Y1510D01*
X556628Y774D01*
X557529Y254D01*
X558535Y-16D01*
X559576D01*
X560581Y254D01*
X561482Y774D01*
X562218Y1510D01*
X562739Y2411D01*
X563008Y3417D01*
Y4457D01*
X562739Y5463D01*
X562218Y6364D01*
X561482Y7100D01*
X560581Y7620D01*
X559576Y7890D01*
D02*
G37*
G36*
X549576D02*
X548535D01*
X547529Y7620D01*
X546628Y7100D01*
X545892Y6364D01*
X545372Y5463D01*
X545102Y4457D01*
Y3417D01*
X545372Y2411D01*
X545892Y1510D01*
X546628Y774D01*
X547529Y254D01*
X548535Y-16D01*
X549576D01*
X550581Y254D01*
X551482Y774D01*
X552218Y1510D01*
X552739Y2411D01*
X553008Y3417D01*
Y4457D01*
X552739Y5463D01*
X552218Y6364D01*
X551482Y7100D01*
X550581Y7620D01*
X549576Y7890D01*
D02*
G37*
G36*
X610594Y-7058D02*
X609878D01*
X609217Y-7332D01*
X608710Y-7839D01*
X608436Y-8500D01*
Y-9216D01*
X608710Y-9878D01*
X609217Y-10384D01*
X609878Y-10658D01*
X610594D01*
X611256Y-10384D01*
X611762Y-9878D01*
X612036Y-9216D01*
Y-8500D01*
X611762Y-7839D01*
X611256Y-7332D01*
X610594Y-7058D01*
D02*
G37*
G36*
X47602D02*
X46886D01*
X46224Y-7332D01*
X45718Y-7839D01*
X45444Y-8500D01*
Y-9216D01*
X45718Y-9878D01*
X46224Y-10384D01*
X46886Y-10658D01*
X47602D01*
X48264Y-10384D01*
X48770Y-9878D01*
X49044Y-9216D01*
Y-8500D01*
X48770Y-7839D01*
X48264Y-7332D01*
X47602Y-7058D01*
D02*
G37*
G36*
X40712D02*
X39996D01*
X39335Y-7332D01*
X38828Y-7839D01*
X38554Y-8500D01*
Y-9216D01*
X38828Y-9878D01*
X39335Y-10384D01*
X39996Y-10658D01*
X40712D01*
X41374Y-10384D01*
X41880Y-9878D01*
X42154Y-9216D01*
Y-8500D01*
X41880Y-7839D01*
X41374Y-7332D01*
X40712Y-7058D01*
D02*
G37*
G36*
X33823D02*
X33106D01*
X32445Y-7332D01*
X31939Y-7839D01*
X31665Y-8500D01*
Y-9216D01*
X31939Y-9878D01*
X32445Y-10384D01*
X33106Y-10658D01*
X33823D01*
X34484Y-10384D01*
X34991Y-9878D01*
X35265Y-9216D01*
Y-8500D01*
X34991Y-7839D01*
X34484Y-7332D01*
X33823Y-7058D01*
D02*
G37*
G36*
X101539Y-16704D02*
X100823D01*
X100162Y-16978D01*
X99655Y-17484D01*
X99381Y-18146D01*
Y-18862D01*
X99655Y-19524D01*
X100162Y-20030D01*
X100823Y-20304D01*
X101539D01*
X102201Y-20030D01*
X102707Y-19524D01*
X102981Y-18862D01*
Y-18146D01*
X102707Y-17484D01*
X102201Y-16978D01*
X101539Y-16704D01*
D02*
G37*
G36*
X641136Y-15466D02*
X640143D01*
X639226Y-15846D01*
X638524Y-16548D01*
X638144Y-17466D01*
Y-18459D01*
X638524Y-19376D01*
X639226Y-20078D01*
X640143Y-20458D01*
X641136D01*
X642054Y-20078D01*
X642756Y-19376D01*
X643136Y-18459D01*
Y-17466D01*
X642756Y-16548D01*
X642054Y-15846D01*
X641136Y-15466D01*
D02*
G37*
G36*
X658823Y-20099D02*
X658107D01*
X657445Y-20373D01*
X656939Y-20880D01*
X656665Y-21541D01*
Y-22257D01*
X656939Y-22919D01*
X657445Y-23425D01*
X658107Y-23699D01*
X658823D01*
X659484Y-23425D01*
X659991Y-22919D01*
X660265Y-22257D01*
Y-21541D01*
X659991Y-20880D01*
X659484Y-20373D01*
X658823Y-20099D01*
D02*
G37*
G36*
X625358D02*
X624642D01*
X623980Y-20373D01*
X623474Y-20880D01*
X623200Y-21541D01*
Y-22257D01*
X623474Y-22919D01*
X623980Y-23425D01*
X624642Y-23699D01*
X625358D01*
X626020Y-23425D01*
X626526Y-22919D01*
X626800Y-22257D01*
Y-21541D01*
X626526Y-20880D01*
X626020Y-20373D01*
X625358Y-20099D01*
D02*
G37*
G36*
X83282Y-19994D02*
X82289D01*
X81372Y-20374D01*
X80669Y-21076D01*
X80289Y-21993D01*
Y-22986D01*
X80669Y-23904D01*
X81372Y-24606D01*
X82289Y-24986D01*
X83282D01*
X84199Y-24606D01*
X84901Y-23904D01*
X85281Y-22986D01*
Y-21993D01*
X84901Y-21076D01*
X84199Y-20374D01*
X83282Y-19994D01*
D02*
G37*
G36*
X609610Y-24775D02*
X608894D01*
X608232Y-25049D01*
X607726Y-25555D01*
X607452Y-26217D01*
Y-26933D01*
X607726Y-27594D01*
X608232Y-28101D01*
X608894Y-28375D01*
X609610D01*
X610272Y-28101D01*
X610778Y-27594D01*
X611052Y-26933D01*
Y-26217D01*
X610778Y-25555D01*
X610272Y-25049D01*
X609610Y-24775D01*
D02*
G37*
G36*
X658823Y-27973D02*
X658107D01*
X657445Y-28247D01*
X656939Y-28754D01*
X656665Y-29415D01*
Y-30131D01*
X656939Y-30793D01*
X657445Y-31299D01*
X658107Y-31573D01*
X658823D01*
X659484Y-31299D01*
X659991Y-30793D01*
X660265Y-30131D01*
Y-29415D01*
X659991Y-28754D01*
X659484Y-28247D01*
X658823Y-27973D01*
D02*
G37*
G36*
X44059Y-28121D02*
X43343D01*
X42681Y-28395D01*
X42175Y-28902D01*
X41901Y-29563D01*
Y-30279D01*
X42175Y-30941D01*
X42681Y-31447D01*
X43343Y-31721D01*
X44059D01*
X44720Y-31447D01*
X45227Y-30941D01*
X45501Y-30279D01*
Y-29563D01*
X45227Y-28902D01*
X44720Y-28395D01*
X44059Y-28121D01*
D02*
G37*
G36*
X56264Y-29696D02*
X55547D01*
X54886Y-29970D01*
X54379Y-30476D01*
X54106Y-31138D01*
Y-31854D01*
X54379Y-32516D01*
X54886Y-33022D01*
X55547Y-33296D01*
X56264D01*
X56925Y-33022D01*
X57432Y-32516D01*
X57705Y-31854D01*
Y-31138D01*
X57432Y-30476D01*
X56925Y-29970D01*
X56264Y-29696D01*
D02*
G37*
G36*
X125949Y-30483D02*
X125233D01*
X124571Y-30757D01*
X124065Y-31264D01*
X123791Y-31925D01*
Y-32642D01*
X124065Y-33303D01*
X124571Y-33809D01*
X125233Y-34084D01*
X125949D01*
X126610Y-33809D01*
X127117Y-33303D01*
X127391Y-32642D01*
Y-31925D01*
X127117Y-31264D01*
X126610Y-30757D01*
X125949Y-30483D01*
D02*
G37*
G36*
X111382Y-31271D02*
X110666D01*
X110004Y-31545D01*
X109498Y-32051D01*
X109224Y-32713D01*
Y-33429D01*
X109498Y-34091D01*
X110004Y-34597D01*
X110666Y-34871D01*
X111382D01*
X112043Y-34597D01*
X112550Y-34091D01*
X112824Y-33429D01*
Y-32713D01*
X112550Y-32051D01*
X112043Y-31545D01*
X111382Y-31271D01*
D02*
G37*
G36*
X641136Y-31214D02*
X640143D01*
X639226Y-31594D01*
X638524Y-32296D01*
X638144Y-33214D01*
Y-34207D01*
X638524Y-35124D01*
X639226Y-35826D01*
X640143Y-36206D01*
X641136D01*
X642054Y-35826D01*
X642756Y-35124D01*
X643136Y-34207D01*
Y-33214D01*
X642756Y-32296D01*
X642054Y-31594D01*
X641136Y-31214D01*
D02*
G37*
G36*
X658823Y-35847D02*
X658107D01*
X657445Y-36121D01*
X656939Y-36628D01*
X656665Y-37289D01*
Y-38005D01*
X656939Y-38667D01*
X657445Y-39173D01*
X658107Y-39447D01*
X658823D01*
X659484Y-39173D01*
X659991Y-38667D01*
X660265Y-38005D01*
Y-37289D01*
X659991Y-36628D01*
X659484Y-36121D01*
X658823Y-35847D01*
D02*
G37*
G36*
X603114Y-37964D02*
X602398D01*
X601736Y-38238D01*
X601230Y-38744D01*
X600956Y-39406D01*
Y-40122D01*
X601230Y-40783D01*
X601736Y-41290D01*
X602398Y-41564D01*
X603114D01*
X603776Y-41290D01*
X604282Y-40783D01*
X604556Y-40122D01*
Y-39406D01*
X604282Y-38744D01*
X603776Y-38238D01*
X603114Y-37964D01*
D02*
G37*
G36*
X64531Y-40720D02*
X63815D01*
X63154Y-40994D01*
X62647Y-41500D01*
X62373Y-42162D01*
Y-42878D01*
X62647Y-43539D01*
X63154Y-44046D01*
X63815Y-44320D01*
X64531D01*
X65193Y-44046D01*
X65699Y-43539D01*
X65973Y-42878D01*
Y-42162D01*
X65699Y-41500D01*
X65193Y-40994D01*
X64531Y-40720D01*
D02*
G37*
G36*
X625358Y-27973D02*
X624642D01*
X623980Y-28247D01*
X623474Y-28754D01*
X623200Y-29415D01*
Y-30131D01*
X623474Y-30793D01*
X623573Y-30891D01*
Y-35458D01*
X623358Y-35602D01*
X622642D01*
X621980Y-35876D01*
X621474Y-36382D01*
X621200Y-37043D01*
Y-37760D01*
X621474Y-38421D01*
X621980Y-38928D01*
X622642Y-39202D01*
X623358D01*
X623573Y-39345D01*
Y-46962D01*
X623474Y-47061D01*
X623200Y-47722D01*
Y-48438D01*
X623474Y-49100D01*
X623980Y-49606D01*
X624642Y-49880D01*
X625358D01*
X626020Y-49606D01*
X626526Y-49100D01*
X626800Y-48438D01*
Y-47722D01*
X626526Y-47061D01*
X626427Y-46962D01*
Y-30891D01*
X626526Y-30793D01*
X626800Y-30131D01*
Y-29415D01*
X626526Y-28754D01*
X626020Y-28247D01*
X625358Y-27973D01*
D02*
G37*
G36*
X659807Y-47413D02*
X659091D01*
X658429Y-47687D01*
X657923Y-48193D01*
X657649Y-48855D01*
Y-49571D01*
X657923Y-50232D01*
X658429Y-50739D01*
X659091Y-51013D01*
X659807D01*
X660468Y-50739D01*
X660975Y-50232D01*
X661249Y-49571D01*
Y-48855D01*
X660975Y-48193D01*
X660468Y-47687D01*
X659807Y-47413D01*
D02*
G37*
G36*
X99768Y-48249D02*
X99051D01*
X98390Y-48523D01*
X97883Y-49029D01*
X97610Y-49691D01*
Y-50407D01*
X97883Y-51069D01*
X98390Y-51575D01*
X99051Y-51849D01*
X99768D01*
X100429Y-51575D01*
X100935Y-51069D01*
X101209Y-50407D01*
Y-49691D01*
X100935Y-49029D01*
X100429Y-48523D01*
X99768Y-48249D01*
D02*
G37*
G36*
X66303D02*
X65587D01*
X64925Y-48523D01*
X64419Y-49029D01*
X64145Y-49691D01*
Y-50407D01*
X64419Y-51069D01*
X64925Y-51575D01*
X65587Y-51849D01*
X66303D01*
X66965Y-51575D01*
X67471Y-51069D01*
X67745Y-50407D01*
Y-49691D01*
X67471Y-49029D01*
X66965Y-48523D01*
X66303Y-48249D01*
D02*
G37*
G36*
X596421Y-52137D02*
X595705D01*
X595043Y-52411D01*
X594537Y-52917D01*
X594263Y-53579D01*
Y-54295D01*
X594537Y-54957D01*
X595043Y-55463D01*
X595705Y-55737D01*
X596421D01*
X597083Y-55463D01*
X597589Y-54957D01*
X597863Y-54295D01*
Y-53579D01*
X597589Y-52917D01*
X597083Y-52411D01*
X596421Y-52137D01*
D02*
G37*
G36*
X83282Y-51490D02*
X82289D01*
X81372Y-51870D01*
X80669Y-52572D01*
X80289Y-53489D01*
Y-54482D01*
X80669Y-55400D01*
X81372Y-56102D01*
X82289Y-56482D01*
X83282D01*
X84199Y-56102D01*
X84901Y-55400D01*
X85281Y-54482D01*
Y-53489D01*
X84901Y-52572D01*
X84199Y-51870D01*
X83282Y-51490D01*
D02*
G37*
G36*
X623586Y-53318D02*
X622870D01*
X622209Y-53592D01*
X621702Y-54098D01*
X621428Y-54760D01*
Y-55476D01*
X621702Y-56138D01*
X622209Y-56644D01*
X622870Y-56918D01*
X623586D01*
X624248Y-56644D01*
X624754Y-56138D01*
X625028Y-55476D01*
Y-54760D01*
X624754Y-54098D01*
X624248Y-53592D01*
X623586Y-53318D01*
D02*
G37*
G36*
X658472Y-54914D02*
X657756D01*
X657094Y-55188D01*
X656588Y-55695D01*
X656314Y-56356D01*
Y-57072D01*
X656588Y-57734D01*
X657094Y-58240D01*
X657756Y-58514D01*
X658472D01*
X659134Y-58240D01*
X659640Y-57734D01*
X659914Y-57072D01*
Y-56356D01*
X659640Y-55695D01*
X659134Y-55188D01*
X658472Y-54914D01*
D02*
G37*
G36*
X99768Y-56123D02*
X99051D01*
X98390Y-56397D01*
X97883Y-56903D01*
X97610Y-57565D01*
Y-58281D01*
X97883Y-58943D01*
X98390Y-59449D01*
X99051Y-59723D01*
X99768D01*
X100429Y-59449D01*
X100935Y-58943D01*
X101209Y-58281D01*
Y-57565D01*
X100935Y-56903D01*
X100429Y-56397D01*
X99768Y-56123D01*
D02*
G37*
G36*
X623869Y-60752D02*
X623153D01*
X622491Y-61026D01*
X621985Y-61533D01*
X621711Y-62194D01*
Y-62910D01*
X621985Y-63572D01*
X622491Y-64078D01*
X623153Y-64352D01*
X623869D01*
X624530Y-64078D01*
X625037Y-63572D01*
X625311Y-62910D01*
Y-62194D01*
X625037Y-61533D01*
X624530Y-61026D01*
X623869Y-60752D01*
D02*
G37*
G36*
X672012Y-60798D02*
X671295D01*
X670634Y-61072D01*
X670128Y-61579D01*
X669853Y-62240D01*
Y-62957D01*
X670128Y-63618D01*
X670634Y-64124D01*
X671295Y-64398D01*
X672012D01*
X672673Y-64124D01*
X673179Y-63618D01*
X673454Y-62957D01*
Y-62240D01*
X673179Y-61579D01*
X672673Y-61072D01*
X672012Y-60798D01*
D02*
G37*
G36*
X657803Y-61725D02*
X657087D01*
X656426Y-62000D01*
X655919Y-62506D01*
X655645Y-63168D01*
Y-63884D01*
X655919Y-64545D01*
X656426Y-65052D01*
X657087Y-65325D01*
X657803D01*
X658465Y-65052D01*
X658971Y-64545D01*
X659245Y-63884D01*
Y-63168D01*
X658971Y-62506D01*
X658465Y-62000D01*
X657803Y-61725D01*
D02*
G37*
G36*
X99768Y-63997D02*
X99051D01*
X98390Y-64271D01*
X97883Y-64777D01*
X97610Y-65439D01*
Y-66155D01*
X97883Y-66817D01*
X98390Y-67323D01*
X99051Y-67597D01*
X99768D01*
X100429Y-67323D01*
X100935Y-66817D01*
X101209Y-66155D01*
Y-65439D01*
X100935Y-64777D01*
X100429Y-64271D01*
X99768Y-63997D01*
D02*
G37*
G36*
X641136Y-62710D02*
X640143D01*
X639226Y-63090D01*
X638524Y-63792D01*
X638144Y-64710D01*
Y-65703D01*
X638524Y-66620D01*
X639226Y-67322D01*
X640143Y-67702D01*
X641136D01*
X642054Y-67322D01*
X642756Y-66620D01*
X643136Y-65703D01*
Y-64710D01*
X642756Y-63792D01*
X642054Y-63090D01*
X641136Y-62710D01*
D02*
G37*
G36*
X83282Y-67238D02*
X82289D01*
X81372Y-67618D01*
X80669Y-68320D01*
X80289Y-69237D01*
Y-70230D01*
X80669Y-71148D01*
X81372Y-71850D01*
X82289Y-72230D01*
X83282D01*
X84199Y-71850D01*
X84901Y-71148D01*
X85281Y-70230D01*
Y-69237D01*
X84901Y-68320D01*
X84199Y-67618D01*
X83282Y-67238D01*
D02*
G37*
G36*
X623980Y-69066D02*
X623264D01*
X622602Y-69340D01*
X622096Y-69846D01*
X621822Y-70508D01*
Y-71224D01*
X622096Y-71886D01*
X622602Y-72392D01*
X623264Y-72666D01*
X623980D01*
X624642Y-72392D01*
X625148Y-71886D01*
X625422Y-71224D01*
Y-70508D01*
X625148Y-69846D01*
X624642Y-69340D01*
X623980Y-69066D01*
D02*
G37*
G36*
X670896Y-72609D02*
X670180D01*
X669519Y-72883D01*
X669488Y-72914D01*
X669458Y-72883D01*
X668796Y-72609D01*
X668080D01*
X667419Y-72883D01*
X666912Y-73390D01*
X666638Y-74051D01*
Y-74768D01*
X666912Y-75429D01*
X667419Y-75935D01*
X668080Y-76209D01*
X668796D01*
X669458Y-75935D01*
X669488Y-75905D01*
X669519Y-75935D01*
X670180Y-76209D01*
X670896D01*
X671558Y-75935D01*
X672064Y-75429D01*
X672338Y-74768D01*
Y-74051D01*
X672064Y-73390D01*
X671558Y-72883D01*
X670896Y-72609D01*
D02*
G37*
G36*
X658411Y-69388D02*
X657695D01*
X657034Y-69662D01*
X656527Y-70169D01*
X656253Y-70830D01*
Y-71546D01*
X656527Y-72208D01*
X657034Y-72714D01*
X657695Y-72988D01*
X658411D01*
X659073Y-72714D01*
X659579Y-72208D01*
X659853Y-71546D01*
Y-70830D01*
X659579Y-70169D01*
X659073Y-69662D01*
X658411Y-69388D01*
D02*
G37*
G36*
X661077Y-73927D02*
X660361D01*
X659699Y-74200D01*
X659193Y-74707D01*
X658919Y-75368D01*
Y-76085D01*
X659193Y-76746D01*
X659699Y-77252D01*
X660361Y-77526D01*
X661077D01*
X661739Y-77252D01*
X662245Y-76746D01*
X662519Y-76085D01*
Y-75368D01*
X662245Y-74707D01*
X661739Y-74200D01*
X661077Y-73927D01*
D02*
G37*
G36*
X597585Y-75303D02*
X596869D01*
X596208Y-75577D01*
X595702Y-76083D01*
X595427Y-76745D01*
Y-77461D01*
X595702Y-78123D01*
X596208Y-78629D01*
X596869Y-78903D01*
X597585D01*
X598247Y-78629D01*
X598753Y-78123D01*
X599027Y-77461D01*
Y-76745D01*
X598753Y-76083D01*
X598247Y-75577D01*
X597585Y-75303D01*
D02*
G37*
G36*
X130279Y-77776D02*
X129563D01*
X128902Y-78050D01*
X128395Y-78557D01*
X128121Y-79218D01*
Y-79934D01*
X128395Y-80596D01*
X128902Y-81102D01*
X129563Y-81376D01*
X130279D01*
X130941Y-81102D01*
X131447Y-80596D01*
X131721Y-79934D01*
Y-79218D01*
X131447Y-78557D01*
X130941Y-78050D01*
X130279Y-77776D01*
D02*
G37*
G36*
X599637Y-81181D02*
X598921D01*
X598259Y-81455D01*
X597753Y-81961D01*
X597479Y-82623D01*
Y-83339D01*
X597753Y-84000D01*
X598259Y-84507D01*
X598921Y-84781D01*
X599637D01*
X600298Y-84507D01*
X600805Y-84000D01*
X601036Y-83442D01*
X601079Y-83339D01*
Y-82623D01*
X600805Y-81961D01*
X600298Y-81455D01*
X600000Y-81331D01*
D01*
X599637Y-81181D01*
D02*
G37*
G36*
X632172Y-81984D02*
X631456D01*
X630795Y-82258D01*
X630289Y-82765D01*
X630015Y-83426D01*
Y-84142D01*
X630289Y-84804D01*
X630795Y-85310D01*
X631456Y-85584D01*
X632172D01*
X632834Y-85310D01*
X633340Y-84804D01*
X633614Y-84142D01*
Y-83426D01*
X633340Y-82765D01*
X632834Y-82258D01*
X632172Y-81984D01*
D02*
G37*
G36*
X589334Y-84421D02*
X588618D01*
X587957Y-84694D01*
X587450Y-85201D01*
X587176Y-85862D01*
Y-86579D01*
X587450Y-87240D01*
X587957Y-87746D01*
X588618Y-88020D01*
X589334D01*
X589996Y-87746D01*
X590502Y-87240D01*
X590776Y-86579D01*
Y-85862D01*
X590502Y-85201D01*
X589996Y-84694D01*
X589334Y-84421D01*
D02*
G37*
G36*
X612563Y-85208D02*
X611847D01*
X611185Y-85482D01*
X610679Y-85988D01*
X610405Y-86650D01*
Y-87366D01*
X610679Y-88028D01*
X611185Y-88534D01*
X611847Y-88808D01*
X612563D01*
X613224Y-88534D01*
X613731Y-88028D01*
X614005Y-87366D01*
Y-86650D01*
X613731Y-85988D01*
X613224Y-85482D01*
X612563Y-85208D01*
D02*
G37*
G36*
X600752Y-85995D02*
X600036D01*
X599374Y-86269D01*
X598868Y-86776D01*
X598594Y-87437D01*
Y-88153D01*
X598868Y-88815D01*
X599374Y-89321D01*
X600036Y-89595D01*
X600752D01*
X601413Y-89321D01*
X601920Y-88815D01*
X602194Y-88153D01*
Y-87437D01*
X601920Y-86776D01*
X601413Y-86269D01*
X600752Y-85995D01*
D02*
G37*
G36*
X629459Y-88337D02*
X628743D01*
X628081Y-88611D01*
X627575Y-89117D01*
X627301Y-89779D01*
Y-90495D01*
X627575Y-91156D01*
X628081Y-91663D01*
X628743Y-91937D01*
X629459D01*
X630120Y-91663D01*
X630626Y-91156D01*
X630901Y-90495D01*
Y-89779D01*
X630626Y-89117D01*
X630120Y-88611D01*
X629459Y-88337D01*
D02*
G37*
G36*
X348672Y-86391D02*
X347750D01*
X346860Y-86629D01*
X346062Y-87090D01*
X345410Y-87742D01*
X344949Y-88540D01*
X344711Y-89430D01*
Y-90352D01*
X344949Y-91242D01*
X345410Y-92040D01*
X346062Y-92691D01*
X346860Y-93152D01*
X347750Y-93391D01*
X348672D01*
X349562Y-93152D01*
X350360Y-92691D01*
X351012Y-92040D01*
X351472Y-91242D01*
X351711Y-90352D01*
Y-89430D01*
X351472Y-88540D01*
X351012Y-87742D01*
X350360Y-87090D01*
X349562Y-86629D01*
X348672Y-86391D01*
D02*
G37*
G36*
X358259Y-86463D02*
X357337D01*
X356447Y-86702D01*
X355649Y-87163D01*
X354997Y-87814D01*
X354537Y-88612D01*
X354298Y-89503D01*
Y-90424D01*
X354537Y-91314D01*
X354997Y-92112D01*
X355649Y-92764D01*
X356447Y-93225D01*
X357337Y-93463D01*
X358259D01*
X359149Y-93225D01*
X359947Y-92764D01*
X360599Y-92112D01*
X361059Y-91314D01*
X361298Y-90424D01*
Y-89503D01*
X361059Y-88612D01*
X360599Y-87814D01*
X359947Y-87163D01*
X359149Y-86702D01*
X358259Y-86463D01*
D02*
G37*
G36*
X104886Y-90375D02*
X104169D01*
X103508Y-90649D01*
X103002Y-91155D01*
X102728Y-91817D01*
Y-92533D01*
X103002Y-93194D01*
X103508Y-93701D01*
X104169Y-93975D01*
X104886D01*
X105547Y-93701D01*
X106053Y-93194D01*
X106328Y-92533D01*
Y-91817D01*
X106053Y-91155D01*
X105547Y-90649D01*
X104886Y-90375D01*
D02*
G37*
G36*
X609413Y-90720D02*
X608697D01*
X608036Y-90994D01*
X607529Y-91500D01*
X607255Y-92162D01*
Y-92878D01*
X607529Y-93539D01*
X608036Y-94046D01*
X608697Y-94320D01*
X609413D01*
X610075Y-94046D01*
X610581Y-93539D01*
X610855Y-92878D01*
Y-92162D01*
X610581Y-91500D01*
X610075Y-90994D01*
X609413Y-90720D01*
D02*
G37*
G36*
X568862Y-86389D02*
X568146D01*
X567484Y-86663D01*
X566978Y-87169D01*
X566704Y-87831D01*
Y-88547D01*
X566978Y-89209D01*
X567484Y-89715D01*
X567694Y-89802D01*
X567773Y-90197D01*
X567746Y-90365D01*
X567491Y-90980D01*
Y-91697D01*
X567532Y-91795D01*
X567198Y-92295D01*
X566965D01*
X566303Y-92568D01*
X565797Y-93075D01*
X565523Y-93736D01*
Y-94453D01*
X565797Y-95114D01*
X566303Y-95621D01*
X566965Y-95894D01*
X567681D01*
X568342Y-95621D01*
X568849Y-95114D01*
X569123Y-94453D01*
Y-93736D01*
X569082Y-93639D01*
X569416Y-93139D01*
X569649D01*
X570311Y-92865D01*
X570817Y-92358D01*
X571091Y-91697D01*
Y-90980D01*
X570817Y-90319D01*
X570311Y-89813D01*
X570101Y-89726D01*
X570022Y-89330D01*
X570049Y-89163D01*
X570304Y-88547D01*
Y-87831D01*
X570030Y-87169D01*
X569524Y-86663D01*
X568862Y-86389D01*
D02*
G37*
G36*
X667287Y-96232D02*
X666571D01*
X665909Y-96505D01*
X665403Y-97012D01*
X665129Y-97673D01*
Y-98390D01*
X665403Y-99051D01*
X665909Y-99558D01*
X666571Y-99831D01*
X667287D01*
X667949Y-99558D01*
X668455Y-99051D01*
X668729Y-98390D01*
Y-97673D01*
X668455Y-97012D01*
X667949Y-96505D01*
X667287Y-96232D01*
D02*
G37*
G36*
X602103Y-96251D02*
X601386D01*
X600725Y-96525D01*
X600219Y-97031D01*
X599944Y-97693D01*
Y-98409D01*
X600219Y-99070D01*
X600725Y-99577D01*
X601386Y-99851D01*
X602103D01*
X602764Y-99577D01*
X603270Y-99070D01*
X603545Y-98409D01*
Y-97693D01*
X603270Y-97031D01*
X602764Y-96525D01*
X602103Y-96251D01*
D02*
G37*
G36*
X585121Y-98316D02*
X584405D01*
X583744Y-98590D01*
X583238Y-99096D01*
X582963Y-99758D01*
Y-100474D01*
X583238Y-101135D01*
X583744Y-101642D01*
X584405Y-101916D01*
X585121D01*
X585783Y-101642D01*
X586087Y-101338D01*
X586167Y-101332D01*
X586646Y-101481D01*
X586846Y-101964D01*
X587353Y-102471D01*
X588014Y-102745D01*
X588730D01*
X589392Y-102471D01*
X589898Y-101964D01*
X590172Y-101303D01*
Y-100587D01*
X589898Y-99925D01*
X589392Y-99419D01*
X588730Y-99145D01*
X588014D01*
X587353Y-99419D01*
X587049Y-99722D01*
X586969Y-99728D01*
X586489Y-99579D01*
X586289Y-99096D01*
X585783Y-98590D01*
X585121Y-98316D01*
D02*
G37*
G36*
X580279Y-100169D02*
X579563D01*
X578902Y-100443D01*
X578395Y-100949D01*
X578121Y-101611D01*
Y-102327D01*
X578395Y-102988D01*
X578902Y-103495D01*
X579563Y-103769D01*
X580279D01*
X580941Y-103495D01*
X581447Y-102988D01*
X581721Y-102327D01*
Y-101611D01*
X581447Y-100949D01*
X580941Y-100443D01*
X580279Y-100169D01*
D02*
G37*
G36*
X98783Y-100562D02*
X98067D01*
X97406Y-100836D01*
X96899Y-101343D01*
X96625Y-102004D01*
Y-102720D01*
X96899Y-103382D01*
X97406Y-103888D01*
X98067Y-104162D01*
X98783D01*
X99445Y-103888D01*
X99951Y-103382D01*
X100225Y-102720D01*
Y-102004D01*
X99951Y-101343D01*
X99445Y-100836D01*
X98783Y-100562D01*
D02*
G37*
G36*
X89925D02*
X89209D01*
X88547Y-100836D01*
X88041Y-101343D01*
X87767Y-102004D01*
Y-102720D01*
X88041Y-103382D01*
X88547Y-103888D01*
X89209Y-104162D01*
X89925D01*
X90587Y-103888D01*
X91093Y-103382D01*
X91367Y-102720D01*
Y-102004D01*
X91093Y-101343D01*
X90587Y-100836D01*
X89925Y-100562D01*
D02*
G37*
G36*
X629492Y-100956D02*
X628776D01*
X628114Y-101230D01*
X627608Y-101736D01*
X627334Y-102398D01*
Y-103114D01*
X627608Y-103776D01*
X628114Y-104282D01*
X628776Y-104556D01*
X629492D01*
X630154Y-104282D01*
X630660Y-103776D01*
X630934Y-103114D01*
Y-102398D01*
X630660Y-101736D01*
X630154Y-101230D01*
X629492Y-100956D01*
D02*
G37*
G36*
X72746Y-83951D02*
X71014D01*
X69304Y-84221D01*
X67657Y-84756D01*
X66115Y-85542D01*
X64714Y-86560D01*
X63490Y-87784D01*
X62472Y-89185D01*
X61686Y-90728D01*
X61151Y-92375D01*
X60880Y-94085D01*
Y-95816D01*
X61151Y-97526D01*
X61686Y-99173D01*
X62472Y-100716D01*
X63490Y-102117D01*
X64714Y-103341D01*
X66115Y-104358D01*
X67657Y-105145D01*
X69304Y-105680D01*
X71014Y-105950D01*
X72746D01*
X74456Y-105680D01*
X76103Y-105145D01*
X77645Y-104358D01*
X79046Y-103341D01*
X80270Y-102117D01*
X81288Y-100716D01*
X82074Y-99173D01*
X82609Y-97526D01*
X82880Y-95816D01*
Y-94085D01*
X82609Y-92375D01*
X82074Y-90728D01*
X81288Y-89185D01*
X80270Y-87784D01*
X79046Y-86560D01*
X77645Y-85542D01*
X76103Y-84756D01*
X74456Y-84221D01*
X72746Y-83951D01*
D02*
G37*
G36*
X528901Y-102414D02*
X528185D01*
X527524Y-102688D01*
X527017Y-103195D01*
X526743Y-103856D01*
Y-104572D01*
X527017Y-105234D01*
X527524Y-105740D01*
X528185Y-106014D01*
X528901D01*
X529563Y-105740D01*
X530069Y-105234D01*
X530343Y-104572D01*
Y-103856D01*
X530069Y-103195D01*
X529563Y-102688D01*
X528901Y-102414D01*
D02*
G37*
G36*
X519059D02*
X518343D01*
X517681Y-102688D01*
X517175Y-103195D01*
X516901Y-103856D01*
Y-104572D01*
X517175Y-105234D01*
X517681Y-105740D01*
X518343Y-106014D01*
X519059D01*
X519720Y-105740D01*
X520227Y-105234D01*
X520501Y-104572D01*
Y-103856D01*
X520227Y-103195D01*
X519720Y-102688D01*
X519059Y-102414D01*
D02*
G37*
G36*
X652411Y-84108D02*
X650680D01*
X648969Y-84379D01*
X647323Y-84914D01*
X645780Y-85700D01*
X644379Y-86717D01*
X643155Y-87942D01*
X642137Y-89343D01*
X641351Y-90885D01*
X640816Y-92532D01*
X640545Y-94242D01*
Y-95973D01*
X640816Y-97684D01*
X641351Y-99330D01*
X642137Y-100873D01*
X643155Y-102274D01*
X644379Y-103498D01*
X645780Y-104516D01*
X647323Y-105302D01*
X648969Y-105837D01*
X650680Y-106108D01*
X652411D01*
X654121Y-105837D01*
X655768Y-105302D01*
X657310Y-104516D01*
X658711Y-103498D01*
X659936Y-102274D01*
X660953Y-100873D01*
X661739Y-99330D01*
X662274Y-97684D01*
X662545Y-95973D01*
Y-94242D01*
X662274Y-92532D01*
X661739Y-90885D01*
X660953Y-89343D01*
X659936Y-87942D01*
X658711Y-86717D01*
X657310Y-85700D01*
X655768Y-84914D01*
X654121Y-84379D01*
X652411Y-84108D01*
D02*
G37*
G36*
X84437Y-103853D02*
X83721D01*
X83060Y-104127D01*
X82553Y-104633D01*
X82279Y-105295D01*
Y-106011D01*
X82553Y-106673D01*
X83060Y-107179D01*
X83721Y-107453D01*
X84437D01*
X85099Y-107179D01*
X85605Y-106673D01*
X85879Y-106011D01*
Y-105295D01*
X85605Y-104633D01*
X85099Y-104127D01*
X84437Y-103853D01*
D02*
G37*
G36*
X500671Y-103934D02*
X499955D01*
X499293Y-104208D01*
X498787Y-104714D01*
X498513Y-105376D01*
Y-106092D01*
X498787Y-106753D01*
X499293Y-107260D01*
X499955Y-107534D01*
X500671D01*
X501333Y-107260D01*
X501839Y-106753D01*
X502113Y-106092D01*
Y-105376D01*
X501839Y-104714D01*
X501333Y-104208D01*
X500671Y-103934D01*
D02*
G37*
G36*
X473586Y-104105D02*
X472870D01*
X472209Y-104379D01*
X471702Y-104886D01*
X471428Y-105547D01*
Y-106264D01*
X471702Y-106925D01*
X472209Y-107431D01*
X472870Y-107705D01*
X473586D01*
X474248Y-107431D01*
X474754Y-106925D01*
X475028Y-106264D01*
Y-105547D01*
X474754Y-104886D01*
X474248Y-104379D01*
X473586Y-104105D01*
D02*
G37*
G36*
X264138Y-104351D02*
X263422D01*
X262760Y-104625D01*
X262254Y-105131D01*
X261980Y-105793D01*
Y-106509D01*
X262254Y-107171D01*
X262760Y-107677D01*
X263422Y-107951D01*
X264138D01*
X264799Y-107677D01*
X265305Y-107171D01*
X265580Y-106509D01*
Y-105793D01*
X265305Y-105131D01*
X264799Y-104625D01*
X264138Y-104351D01*
D02*
G37*
G36*
X668075Y-104893D02*
X667358D01*
X666697Y-105167D01*
X666191Y-105673D01*
X665916Y-106335D01*
Y-107051D01*
X666191Y-107712D01*
X666697Y-108219D01*
X667358Y-108493D01*
X668075D01*
X668736Y-108219D01*
X669242Y-107712D01*
X669517Y-107051D01*
Y-106335D01*
X669242Y-105673D01*
X668736Y-105167D01*
X668075Y-104893D01*
D02*
G37*
G36*
X245022Y-105152D02*
X244306D01*
X243644Y-105426D01*
X243138Y-105932D01*
X242864Y-106594D01*
Y-107310D01*
X243138Y-107972D01*
X243644Y-108478D01*
X244306Y-108752D01*
X245022D01*
X245683Y-108478D01*
X246190Y-107972D01*
X246464Y-107310D01*
Y-106594D01*
X246190Y-105932D01*
X245683Y-105426D01*
X245022Y-105152D01*
D02*
G37*
G36*
X662897Y-105266D02*
X662181D01*
X661519Y-105540D01*
X661013Y-106046D01*
X660739Y-106708D01*
Y-107424D01*
X661013Y-108085D01*
X661519Y-108592D01*
X662181Y-108866D01*
X662897D01*
X663559Y-108592D01*
X664065Y-108085D01*
X664339Y-107424D01*
Y-106708D01*
X664065Y-106046D01*
X663559Y-105540D01*
X662897Y-105266D01*
D02*
G37*
G36*
X107704Y-108436D02*
X106988D01*
X106327Y-108710D01*
X105821Y-109217D01*
X105608Y-109729D01*
X105085D01*
X104872Y-109217D01*
X104366Y-108710D01*
X103705Y-108436D01*
X102988D01*
X102327Y-108710D01*
X101821Y-109217D01*
X101608Y-109729D01*
X101084D01*
X100872Y-109217D01*
X100366Y-108710D01*
X99704Y-108436D01*
X98988D01*
X98327Y-108710D01*
X97821Y-109217D01*
X97546Y-109878D01*
Y-110405D01*
X96925D01*
X96264Y-110679D01*
X95758Y-111185D01*
X95483Y-111847D01*
Y-112563D01*
X95758Y-113224D01*
X96264Y-113731D01*
X96925Y-114005D01*
X97641D01*
X98303Y-113731D01*
X98809Y-113224D01*
X99022Y-112712D01*
X99545D01*
X99757Y-113224D01*
X100264Y-113731D01*
X100925Y-114005D01*
X101641D01*
X102303Y-113731D01*
X102809Y-113224D01*
X103084Y-112563D01*
X103547D01*
X103821Y-113224D01*
X104327Y-113731D01*
X104988Y-114005D01*
X105704D01*
X106366Y-113731D01*
X106872Y-113224D01*
X107147Y-112563D01*
X107609Y-112594D01*
X107884Y-113256D01*
X108390Y-113762D01*
X109051Y-114036D01*
X109767D01*
X110429Y-113762D01*
X110935Y-113256D01*
X111209Y-112594D01*
Y-111878D01*
X110935Y-111217D01*
X110429Y-110710D01*
X109767Y-110436D01*
X109146D01*
Y-109878D01*
X108872Y-109217D01*
X108366Y-108710D01*
X107704Y-108436D01*
D02*
G37*
G36*
X569450Y-106248D02*
X568734D01*
X568072Y-106522D01*
X567566Y-107029D01*
X567292Y-107690D01*
Y-108406D01*
X567566Y-109068D01*
X568072Y-109574D01*
X568734Y-109848D01*
X569450D01*
X570111Y-109574D01*
X570618Y-109068D01*
X570892Y-108406D01*
Y-107690D01*
X570618Y-107029D01*
X570111Y-106522D01*
X569450Y-106248D01*
D02*
G37*
G36*
X546744Y-107224D02*
X546028D01*
X545366Y-107498D01*
X544860Y-108004D01*
X544586Y-108666D01*
Y-109382D01*
X544860Y-110044D01*
X545366Y-110550D01*
X546028Y-110824D01*
X546744D01*
X547406Y-110550D01*
X547912Y-110044D01*
X548186Y-109382D01*
Y-108666D01*
X547912Y-108004D01*
X547406Y-107498D01*
X546744Y-107224D01*
D02*
G37*
G36*
X254071Y-107390D02*
X253355D01*
X252693Y-107664D01*
X252187Y-108170D01*
X251913Y-108832D01*
Y-109548D01*
X252187Y-110210D01*
X252693Y-110716D01*
X253355Y-110990D01*
X254071D01*
X254732Y-110716D01*
X255239Y-110210D01*
X255513Y-109548D01*
Y-108832D01*
X255239Y-108170D01*
X254732Y-107664D01*
X254071Y-107390D01*
D02*
G37*
G36*
X355083Y-111979D02*
X354366D01*
X353740Y-112239D01*
X353114Y-111979D01*
X352398D01*
X351772Y-112239D01*
X351145Y-111979D01*
X350429D01*
X349768Y-112254D01*
X349261Y-112760D01*
X348987Y-113421D01*
Y-114138D01*
X349261Y-114799D01*
X349490Y-115028D01*
X349732Y-115354D01*
X349490Y-115681D01*
X349261Y-115910D01*
X348987Y-116571D01*
Y-117287D01*
X349261Y-117949D01*
X349768Y-118455D01*
X350429Y-118729D01*
X351145D01*
X351772Y-118470D01*
X352398Y-118729D01*
X353114D01*
X353740Y-118470D01*
X354366Y-118729D01*
X355083D01*
X355744Y-118455D01*
X356250Y-117949D01*
X356524Y-117287D01*
Y-116571D01*
X356250Y-115910D01*
X356022Y-115681D01*
X355780Y-115354D01*
X356022Y-115028D01*
X356250Y-114799D01*
X356524Y-114138D01*
Y-113421D01*
X356250Y-112760D01*
X355744Y-112254D01*
X355083Y-111979D01*
D02*
G37*
G36*
X246421Y-109224D02*
X245705D01*
X245043Y-109498D01*
X244537Y-110004D01*
X244263Y-110666D01*
Y-111382D01*
X244537Y-112043D01*
X245043Y-112550D01*
X245705Y-112824D01*
X246421D01*
X247083Y-112550D01*
X247589Y-112043D01*
X247863Y-111382D01*
Y-110666D01*
X247589Y-110004D01*
X247083Y-109498D01*
X246421Y-109224D01*
D02*
G37*
G36*
X257255Y-110201D02*
X256539D01*
X255877Y-110475D01*
X255371Y-110981D01*
X255097Y-111643D01*
Y-112359D01*
X255371Y-113020D01*
X255877Y-113527D01*
X256539Y-113801D01*
X257255D01*
X257916Y-113527D01*
X258423Y-113020D01*
X258697Y-112359D01*
Y-111643D01*
X258423Y-110981D01*
X257916Y-110475D01*
X257255Y-110201D01*
D02*
G37*
G36*
X309374Y-112186D02*
X308658D01*
X307996Y-112460D01*
X307490Y-112966D01*
X307216Y-113628D01*
Y-114344D01*
X307490Y-115005D01*
X307996Y-115512D01*
X308658Y-115786D01*
X309374D01*
X310035Y-115512D01*
X310542Y-115005D01*
X310816Y-114344D01*
Y-113628D01*
X310542Y-112966D01*
X310035Y-112460D01*
X309374Y-112186D01*
D02*
G37*
G36*
X194256Y-113209D02*
X193540D01*
X192878Y-113484D01*
X192372Y-113990D01*
X192098Y-114651D01*
Y-115367D01*
X192372Y-116029D01*
X192878Y-116535D01*
X193540Y-116809D01*
X194256D01*
X194917Y-116535D01*
X195424Y-116029D01*
X195698Y-115367D01*
Y-114651D01*
X195424Y-113990D01*
X194917Y-113484D01*
X194256Y-113209D01*
D02*
G37*
G36*
X538941Y-110011D02*
X538225D01*
X537563Y-110285D01*
X537057Y-110791D01*
X536783Y-111453D01*
Y-112169D01*
X537057Y-112831D01*
X537563Y-113337D01*
X538225Y-113611D01*
X538336D01*
X538436Y-114111D01*
X538213Y-114203D01*
X537707Y-114709D01*
X537433Y-115371D01*
Y-116087D01*
X537707Y-116749D01*
X538213Y-117255D01*
X538875Y-117529D01*
X539591D01*
X540252Y-117255D01*
X540759Y-116749D01*
X541033Y-116087D01*
Y-115371D01*
X540759Y-114709D01*
X540252Y-114203D01*
X539591Y-113929D01*
X539479D01*
X539380Y-113429D01*
X539602Y-113337D01*
X540109Y-112831D01*
X540383Y-112169D01*
Y-111453D01*
X540109Y-110791D01*
X539602Y-110285D01*
X538941Y-110011D01*
D02*
G37*
G36*
X463909Y-114225D02*
X463193D01*
X462532Y-114499D01*
X462025Y-115006D01*
X461751Y-115667D01*
Y-116383D01*
X462025Y-117045D01*
X462532Y-117551D01*
X463193Y-117825D01*
X463909D01*
X464571Y-117551D01*
X465077Y-117045D01*
X465351Y-116383D01*
Y-115667D01*
X465077Y-115006D01*
X464571Y-114499D01*
X463909Y-114225D01*
D02*
G37*
G36*
X457100Y-114243D02*
X456384D01*
X455723Y-114517D01*
X455216Y-115023D01*
X454942Y-115685D01*
Y-116401D01*
X455216Y-117062D01*
X455723Y-117569D01*
X456384Y-117843D01*
X457100D01*
X457762Y-117569D01*
X458268Y-117062D01*
X458542Y-116401D01*
Y-115685D01*
X458268Y-115023D01*
X457762Y-114517D01*
X457100Y-114243D01*
D02*
G37*
G36*
X502027Y-114801D02*
X501311D01*
X500649Y-115075D01*
X500143Y-115581D01*
X499869Y-116243D01*
Y-116959D01*
X500143Y-117621D01*
X500649Y-118127D01*
X501311Y-118401D01*
X502027D01*
X502689Y-118127D01*
X503195Y-117621D01*
X503469Y-116959D01*
Y-116243D01*
X503195Y-115581D01*
X502689Y-115075D01*
X502027Y-114801D01*
D02*
G37*
G36*
X62857Y-115455D02*
X62141D01*
X61479Y-115729D01*
X60973Y-116236D01*
X60699Y-116897D01*
Y-117613D01*
X60973Y-118275D01*
X61479Y-118781D01*
X62141Y-119055D01*
X62857D01*
X63519Y-118781D01*
X64025Y-118275D01*
X64299Y-117613D01*
Y-116897D01*
X64025Y-116236D01*
X63519Y-115729D01*
X62857Y-115455D01*
D02*
G37*
G36*
X585791Y-113161D02*
X585075D01*
X584413Y-113435D01*
X583907Y-113941D01*
X583633Y-114603D01*
Y-115319D01*
X583883Y-115921D01*
X583232Y-116191D01*
X582726Y-116697D01*
X582452Y-117359D01*
Y-118075D01*
X582726Y-118736D01*
X583232Y-119243D01*
X583894Y-119517D01*
X584610D01*
X585272Y-119243D01*
X585778Y-118736D01*
X586052Y-118075D01*
Y-117359D01*
X585802Y-116756D01*
X586453Y-116487D01*
X586959Y-115980D01*
X587233Y-115319D01*
Y-114603D01*
X586959Y-113941D01*
X586453Y-113435D01*
X585791Y-113161D01*
D02*
G37*
G36*
X315319Y-117147D02*
X314603D01*
X313941Y-117420D01*
X313435Y-117927D01*
X313161Y-118588D01*
Y-119305D01*
X313435Y-119966D01*
X313941Y-120472D01*
X314603Y-120747D01*
X315319D01*
X315980Y-120472D01*
X316487Y-119966D01*
X316761Y-119305D01*
Y-118588D01*
X316487Y-117927D01*
X315980Y-117420D01*
X315319Y-117147D01*
D02*
G37*
G36*
X108072Y-119669D02*
X107282D01*
X106553Y-119971D01*
X105995Y-120529D01*
X105782Y-121043D01*
X105241D01*
X105029Y-120529D01*
X104471Y-119971D01*
X103741Y-119669D01*
X102952D01*
X102223Y-119971D01*
X101664Y-120529D01*
X101452Y-121043D01*
X100910D01*
X100698Y-120529D01*
X100140Y-119971D01*
X99410Y-119669D01*
X98621D01*
X97892Y-119971D01*
X97334Y-120529D01*
X97031Y-121259D01*
Y-122048D01*
X97334Y-122777D01*
X97892Y-123336D01*
X98405Y-123548D01*
Y-124090D01*
X97892Y-124302D01*
X97334Y-124860D01*
X97031Y-125590D01*
Y-126379D01*
X97334Y-127108D01*
X97892Y-127666D01*
X98405Y-127879D01*
Y-128420D01*
X97892Y-128633D01*
X97334Y-129191D01*
X97031Y-129920D01*
Y-130710D01*
X97334Y-131439D01*
X97892Y-131997D01*
X98621Y-132299D01*
X99410D01*
X100140Y-131997D01*
X100698Y-131439D01*
X100910Y-130926D01*
X101452D01*
X101664Y-131439D01*
X102223Y-131997D01*
X102952Y-132299D01*
X103741D01*
X104471Y-131997D01*
X105029Y-131439D01*
X105241Y-130926D01*
X105782D01*
X105995Y-131439D01*
X106553Y-131997D01*
X107282Y-132299D01*
X108072D01*
X108801Y-131997D01*
X109359Y-131439D01*
X109661Y-130710D01*
Y-129920D01*
X109359Y-129191D01*
X108801Y-128633D01*
X108288Y-128420D01*
Y-127879D01*
X108801Y-127666D01*
X109359Y-127108D01*
X109661Y-126379D01*
Y-125590D01*
X109359Y-124860D01*
X108801Y-124302D01*
X108288Y-124090D01*
Y-123548D01*
X108801Y-123336D01*
X109359Y-122777D01*
X109661Y-122048D01*
Y-121259D01*
X109359Y-120529D01*
X108801Y-119971D01*
X108072Y-119669D01*
D02*
G37*
G36*
X194256Y-118131D02*
X193540D01*
X192878Y-118405D01*
X192372Y-118911D01*
X192098Y-119573D01*
Y-120289D01*
X192372Y-120950D01*
X192878Y-121457D01*
X193540Y-121731D01*
X194256D01*
X194917Y-121457D01*
X195424Y-120950D01*
X195698Y-120289D01*
Y-119573D01*
X195424Y-118911D01*
X194917Y-118405D01*
X194256Y-118131D01*
D02*
G37*
G36*
X172029Y-116028D02*
X170963D01*
X169932Y-116304D01*
X169009Y-116837D01*
X168254Y-117591D01*
X167721Y-118515D01*
X167445Y-119545D01*
Y-120612D01*
X167721Y-121642D01*
X168254Y-122566D01*
X169009Y-123320D01*
X169932Y-123854D01*
X170963Y-124130D01*
X172029D01*
X173060Y-123854D01*
X173984Y-123320D01*
X174738Y-122566D01*
X175271Y-121642D01*
X175547Y-120612D01*
Y-119545D01*
X175271Y-118515D01*
X174738Y-117591D01*
X173984Y-116837D01*
X173060Y-116304D01*
X172029Y-116028D01*
D02*
G37*
G36*
X162029D02*
X160963D01*
X159932Y-116304D01*
X159009Y-116837D01*
X158254Y-117591D01*
X157721Y-118515D01*
X157445Y-119545D01*
Y-120612D01*
X157721Y-121642D01*
X158254Y-122566D01*
X159009Y-123320D01*
X159932Y-123854D01*
X160963Y-124130D01*
X162029D01*
X163060Y-123854D01*
X163984Y-123320D01*
X164738Y-122566D01*
X165271Y-121642D01*
X165547Y-120612D01*
Y-119545D01*
X165271Y-118515D01*
X164738Y-117591D01*
X163984Y-116837D01*
X163060Y-116304D01*
X162029Y-116028D01*
D02*
G37*
G36*
X152029D02*
X150963D01*
X149932Y-116304D01*
X149009Y-116837D01*
X148254Y-117591D01*
X147721Y-118515D01*
X147445Y-119545D01*
Y-120612D01*
X147721Y-121642D01*
X148254Y-122566D01*
X149009Y-123320D01*
X149932Y-123854D01*
X150963Y-124130D01*
X152029D01*
X153060Y-123854D01*
X153983Y-123320D01*
X154738Y-122566D01*
X155271Y-121642D01*
X155547Y-120612D01*
Y-119545D01*
X155271Y-118515D01*
X154738Y-117591D01*
X153983Y-116837D01*
X153060Y-116304D01*
X152029Y-116028D01*
D02*
G37*
G36*
X142029D02*
X140963D01*
X139932Y-116304D01*
X139009Y-116837D01*
X138254Y-117591D01*
X137721Y-118515D01*
X137445Y-119545D01*
Y-120612D01*
X137721Y-121642D01*
X138254Y-122566D01*
X139009Y-123320D01*
X139932Y-123854D01*
X140963Y-124130D01*
X142029D01*
X143060Y-123854D01*
X143983Y-123320D01*
X144738Y-122566D01*
X145271Y-121642D01*
X145547Y-120612D01*
Y-119545D01*
X145271Y-118515D01*
X144738Y-117591D01*
X143983Y-116837D01*
X143060Y-116304D01*
X142029Y-116028D01*
D02*
G37*
G36*
X470830Y-121822D02*
X470114D01*
X469453Y-122096D01*
X468947Y-122602D01*
X468673Y-123264D01*
Y-123980D01*
X468947Y-124642D01*
X469453Y-125148D01*
X470114Y-125422D01*
X470830D01*
X471492Y-125148D01*
X471998Y-124642D01*
X472272Y-123980D01*
Y-123264D01*
X471998Y-122602D01*
X471492Y-122096D01*
X470830Y-121822D01*
D02*
G37*
G36*
X309413Y-122068D02*
X308697D01*
X308035Y-122342D01*
X307529Y-122848D01*
X307255Y-123510D01*
Y-124226D01*
X307529Y-124887D01*
X308035Y-125394D01*
X308697Y-125668D01*
X309413D01*
X310075Y-125394D01*
X310581Y-124887D01*
X310855Y-124226D01*
Y-123510D01*
X310581Y-122848D01*
X310075Y-122342D01*
X309413Y-122068D01*
D02*
G37*
G36*
X241608Y-124447D02*
X240892D01*
X240230Y-124721D01*
X239724Y-125227D01*
X239450Y-125889D01*
Y-126605D01*
X239724Y-127267D01*
X240230Y-127773D01*
X240892Y-128047D01*
X241608D01*
X242269Y-127773D01*
X242776Y-127267D01*
X243050Y-126605D01*
Y-125889D01*
X242776Y-125227D01*
X242269Y-124721D01*
X241608Y-124447D01*
D02*
G37*
G36*
X477130Y-121822D02*
X476414D01*
X475752Y-122096D01*
X475246Y-122602D01*
X474972Y-123264D01*
Y-123980D01*
X475246Y-124642D01*
X475507Y-124903D01*
X475369Y-125472D01*
X474965Y-125639D01*
X474458Y-126146D01*
X474184Y-126807D01*
Y-127523D01*
X474458Y-128185D01*
X474965Y-128691D01*
X475626Y-128965D01*
X476342D01*
X477004Y-128691D01*
X477510Y-128185D01*
X477784Y-127523D01*
Y-126807D01*
X477510Y-126146D01*
X477248Y-125884D01*
X477387Y-125315D01*
X477791Y-125148D01*
X478298Y-124642D01*
X478572Y-123980D01*
Y-123264D01*
X478298Y-122602D01*
X477791Y-122096D01*
X477130Y-121822D01*
D02*
G37*
G36*
X532159Y-125695D02*
X531443D01*
X530781Y-125969D01*
X530275Y-126476D01*
X530001Y-127137D01*
Y-127853D01*
X530275Y-128515D01*
X530781Y-129021D01*
X531443Y-129295D01*
X532159D01*
X532821Y-129021D01*
X533327Y-128515D01*
X533601Y-127853D01*
Y-127137D01*
X533327Y-126476D01*
X532821Y-125969D01*
X532159Y-125695D01*
D02*
G37*
G36*
X524964Y-124036D02*
X524248D01*
X523587Y-124310D01*
X523080Y-124817D01*
X522806Y-125478D01*
Y-126194D01*
X523080Y-126856D01*
X523488Y-127263D01*
X523031Y-127720D01*
X522757Y-128382D01*
Y-129098D01*
X523031Y-129759D01*
X523537Y-130266D01*
X524199Y-130540D01*
X524915D01*
X525577Y-130266D01*
X526083Y-129759D01*
X526357Y-129098D01*
Y-128382D01*
X526083Y-127720D01*
X525675Y-127313D01*
X526132Y-126856D01*
X526406Y-126194D01*
Y-125478D01*
X526132Y-124817D01*
X525626Y-124310D01*
X524964Y-124036D01*
D02*
G37*
G36*
X506565Y-125533D02*
X505849D01*
X505187Y-125807D01*
X504681Y-126313D01*
X504407Y-126975D01*
Y-127691D01*
X504681Y-128352D01*
X505002Y-128673D01*
X504773Y-128902D01*
X504499Y-129563D01*
Y-130279D01*
X504773Y-130941D01*
X505280Y-131447D01*
X505941Y-131721D01*
X506657D01*
X507319Y-131447D01*
X507825Y-130941D01*
X508099Y-130279D01*
Y-129563D01*
X507825Y-128902D01*
X507504Y-128581D01*
X507733Y-128352D01*
X508007Y-127691D01*
Y-126975D01*
X507733Y-126313D01*
X507227Y-125807D01*
X506565Y-125533D01*
D02*
G37*
G36*
X145229Y-129809D02*
X144513D01*
X143851Y-130083D01*
X143345Y-130590D01*
X143071Y-131251D01*
Y-131967D01*
X143345Y-132629D01*
X143851Y-133135D01*
X144513Y-133409D01*
X145229D01*
X145891Y-133135D01*
X146397Y-132629D01*
X146671Y-131967D01*
Y-131251D01*
X146397Y-130590D01*
X145891Y-130083D01*
X145229Y-129809D01*
D02*
G37*
G36*
X76145Y-130090D02*
X75429D01*
X74768Y-130364D01*
X74261Y-130870D01*
X73987Y-131532D01*
Y-132248D01*
X74261Y-132909D01*
X74768Y-133416D01*
X75429Y-133690D01*
X76145D01*
X76807Y-133416D01*
X77313Y-132909D01*
X77587Y-132248D01*
Y-131532D01*
X77313Y-130870D01*
X76807Y-130364D01*
X76145Y-130090D01*
D02*
G37*
G36*
X117484Y-118121D02*
X116768D01*
X116106Y-118395D01*
X115600Y-118902D01*
X115326Y-119563D01*
Y-120279D01*
X115600Y-120941D01*
X116106Y-121447D01*
X116768Y-121721D01*
X117295D01*
Y-122247D01*
X116768D01*
X116106Y-122521D01*
X115600Y-123027D01*
X115326Y-123689D01*
Y-124405D01*
X115600Y-125066D01*
X116106Y-125573D01*
X116618Y-125785D01*
Y-126309D01*
X116106Y-126521D01*
X115600Y-127027D01*
X115326Y-127689D01*
Y-128405D01*
X115600Y-129066D01*
X116106Y-129573D01*
X116620Y-129785D01*
Y-130309D01*
X116106Y-130521D01*
X115600Y-131028D01*
X115326Y-131689D01*
Y-132405D01*
X115600Y-133067D01*
X116106Y-133573D01*
X116768Y-133847D01*
X117484D01*
X118146Y-133573D01*
X118652Y-133067D01*
X118926Y-132405D01*
Y-131847D01*
X119453D01*
X120114Y-131573D01*
X120621Y-131066D01*
X120895Y-130405D01*
Y-129689D01*
X120621Y-129027D01*
X120114Y-128521D01*
X119602Y-128309D01*
Y-127785D01*
X120114Y-127573D01*
X120621Y-127066D01*
X120895Y-126405D01*
Y-125689D01*
X120621Y-125027D01*
X120114Y-124521D01*
X119602Y-124309D01*
Y-123785D01*
X120114Y-123573D01*
X120621Y-123066D01*
X120895Y-122405D01*
Y-121689D01*
X120621Y-121027D01*
X120114Y-120521D01*
X119453Y-120247D01*
X118926D01*
Y-119563D01*
X118652Y-118902D01*
X118146Y-118395D01*
X117484Y-118121D01*
D02*
G37*
G36*
X488941Y-130483D02*
X488225D01*
X487563Y-130757D01*
X487057Y-131264D01*
X486783Y-131925D01*
Y-132641D01*
X487057Y-133303D01*
X487563Y-133809D01*
X488225Y-134083D01*
X488941D01*
X489602Y-133809D01*
X490109Y-133303D01*
X490383Y-132641D01*
Y-131925D01*
X490109Y-131264D01*
X489602Y-130757D01*
X488941Y-130483D01*
D02*
G37*
G36*
X480478Y-130565D02*
X479762D01*
X479100Y-130839D01*
X478594Y-131345D01*
X478320Y-132007D01*
Y-132723D01*
X478594Y-133384D01*
X479100Y-133891D01*
X479762Y-134165D01*
X480478D01*
X481139Y-133891D01*
X481646Y-133384D01*
X481920Y-132723D01*
Y-132007D01*
X481646Y-131345D01*
X481139Y-130839D01*
X480478Y-130565D01*
D02*
G37*
G36*
X267681Y-130877D02*
X266965D01*
X266303Y-131151D01*
X265797Y-131658D01*
X265523Y-132319D01*
Y-133035D01*
X265797Y-133697D01*
X266303Y-134203D01*
X266965Y-134477D01*
X267681D01*
X268342Y-134203D01*
X268849Y-133697D01*
X269123Y-133035D01*
Y-132319D01*
X268849Y-131658D01*
X268342Y-131151D01*
X267681Y-130877D01*
D02*
G37*
G36*
X234610Y-131942D02*
X233894D01*
X233232Y-132216D01*
X232726Y-132722D01*
X232452Y-133384D01*
Y-134100D01*
X232726Y-134761D01*
X233232Y-135268D01*
X233894Y-135542D01*
X234610D01*
X235272Y-135268D01*
X235778Y-134761D01*
X236052Y-134100D01*
Y-133384D01*
X235778Y-132722D01*
X235272Y-132216D01*
X234610Y-131942D01*
D02*
G37*
G36*
X519945Y-132796D02*
X519229D01*
X518567Y-133070D01*
X518061Y-133576D01*
X517787Y-134238D01*
Y-134954D01*
X518061Y-135616D01*
X518567Y-136122D01*
X519229Y-136396D01*
X519945D01*
X520606Y-136122D01*
X521113Y-135616D01*
X521387Y-134954D01*
Y-134238D01*
X521113Y-133576D01*
X520606Y-133070D01*
X519945Y-132796D01*
D02*
G37*
G36*
X109767Y-138311D02*
X109051D01*
X108390Y-138585D01*
X107884Y-139091D01*
X107671Y-139603D01*
X107148D01*
X106935Y-139091D01*
X106429Y-138585D01*
X105768Y-138311D01*
X105051D01*
X104390Y-138585D01*
X103884Y-139091D01*
X103671Y-139603D01*
X103147D01*
X102935Y-139091D01*
X102429Y-138585D01*
X101768Y-138311D01*
X101051D01*
X100390Y-138585D01*
X99884Y-139091D01*
X99671Y-139603D01*
X99147D01*
X98935Y-139091D01*
X98429Y-138585D01*
X97768Y-138311D01*
X97051D01*
X96390Y-138585D01*
X95884Y-139091D01*
X95609Y-139753D01*
Y-140469D01*
X95884Y-141131D01*
X96390Y-141637D01*
X97051Y-141911D01*
X97610D01*
Y-142090D01*
X97883Y-142752D01*
X98390Y-143258D01*
X99051Y-143532D01*
X99768D01*
X100429Y-143258D01*
X100935Y-142752D01*
X101147Y-142240D01*
X101671D01*
X101883Y-142752D01*
X102390Y-143258D01*
X103051Y-143532D01*
X103768D01*
X104429Y-143258D01*
X104935Y-142752D01*
X105148Y-142240D01*
X105671D01*
X105884Y-142752D01*
X106390Y-143258D01*
X107051Y-143532D01*
X107767D01*
X108429Y-143258D01*
X108935Y-142752D01*
X109209Y-142090D01*
Y-141911D01*
X109767D01*
X110429Y-141637D01*
X110935Y-141131D01*
X111209Y-140469D01*
Y-139753D01*
X110935Y-139091D01*
X110429Y-138585D01*
X109767Y-138311D01*
D02*
G37*
G36*
X87612Y-137829D02*
X86896D01*
X86235Y-138103D01*
X85728Y-138609D01*
X85454Y-139271D01*
Y-139987D01*
X85728Y-140648D01*
X86235Y-141155D01*
X86896Y-141429D01*
X87612D01*
X88027Y-141257D01*
X88041Y-141290D01*
X88547Y-141796D01*
X89209Y-142070D01*
X89925D01*
X90587Y-141796D01*
X91093Y-141290D01*
X91367Y-140628D01*
Y-139912D01*
X91093Y-139251D01*
X90587Y-138744D01*
X89925Y-138470D01*
X89209D01*
X88794Y-138642D01*
X88780Y-138609D01*
X88274Y-138103D01*
X87612Y-137829D01*
D02*
G37*
G36*
X673080Y-128795D02*
X671721D01*
X670388Y-129060D01*
X669132Y-129580D01*
X668002Y-130335D01*
X667041Y-131296D01*
X666286Y-132427D01*
X665766Y-133682D01*
X665501Y-135015D01*
Y-136374D01*
X665766Y-137708D01*
X666286Y-138963D01*
X667041Y-140093D01*
X668002Y-141054D01*
X669132Y-141810D01*
X670388Y-142330D01*
X671721Y-142595D01*
X673080D01*
X674413Y-142330D01*
X675669Y-141810D01*
X676799Y-141054D01*
X677760Y-140093D01*
X678515Y-138963D01*
X679036Y-137708D01*
X679301Y-136374D01*
Y-135015D01*
X679036Y-133682D01*
X678515Y-132427D01*
X677760Y-131296D01*
X676799Y-130335D01*
X675669Y-129580D01*
X674413Y-129060D01*
X673080Y-128795D01*
D02*
G37*
G36*
X72208Y-145838D02*
X71492D01*
X70831Y-146112D01*
X70324Y-146618D01*
X70050Y-147280D01*
Y-147996D01*
X70324Y-148657D01*
X70831Y-149164D01*
X71492Y-149438D01*
X72208D01*
X72870Y-149164D01*
X73376Y-148657D01*
X73650Y-147996D01*
Y-147280D01*
X73376Y-146618D01*
X72870Y-146112D01*
X72208Y-145838D01*
D02*
G37*
G36*
X657838Y-162767D02*
X657122D01*
X656461Y-163041D01*
X655954Y-163547D01*
X655680Y-164209D01*
Y-164925D01*
X655954Y-165587D01*
X656461Y-166093D01*
X657122Y-166367D01*
X657838D01*
X658500Y-166093D01*
X659006Y-165587D01*
X659280Y-164925D01*
Y-164209D01*
X659006Y-163547D01*
X658500Y-163041D01*
X657838Y-162767D01*
D02*
G37*
G36*
X668862Y-163161D02*
X668146D01*
X667484Y-163435D01*
X666978Y-163941D01*
X666704Y-164603D01*
Y-165319D01*
X666978Y-165980D01*
X667484Y-166487D01*
X668146Y-166761D01*
X668862D01*
X669524Y-166487D01*
X670030Y-165980D01*
X670304Y-165319D01*
Y-164603D01*
X670030Y-163941D01*
X669524Y-163435D01*
X668862Y-163161D01*
D02*
G37*
G36*
X663350D02*
X662634D01*
X661973Y-163435D01*
X661466Y-163941D01*
X661192Y-164603D01*
Y-165319D01*
X661466Y-165980D01*
X661973Y-166487D01*
X662634Y-166761D01*
X663350D01*
X664012Y-166487D01*
X664518Y-165980D01*
X664792Y-165319D01*
Y-164603D01*
X664518Y-163941D01*
X664012Y-163435D01*
X663350Y-163161D01*
D02*
G37*
G36*
X653114D02*
X652398D01*
X651736Y-163435D01*
X651230Y-163941D01*
X650956Y-164603D01*
Y-165319D01*
X651230Y-165980D01*
X651736Y-166487D01*
X652398Y-166761D01*
X653114D01*
X653776Y-166487D01*
X654282Y-165980D01*
X654556Y-165319D01*
Y-164603D01*
X654282Y-163941D01*
X653776Y-163435D01*
X653114Y-163161D01*
D02*
G37*
G36*
X68932Y-177521D02*
X68215D01*
X67554Y-177795D01*
X67048Y-178301D01*
X66773Y-178963D01*
Y-179679D01*
X67048Y-180340D01*
X67554Y-180847D01*
X68215Y-181121D01*
X68932D01*
X69593Y-180847D01*
X70099Y-180340D01*
X70373Y-179679D01*
Y-178963D01*
X70099Y-178301D01*
X69593Y-177795D01*
X68932Y-177521D01*
D02*
G37*
G36*
X64334Y-225562D02*
X63618D01*
X62957Y-225836D01*
X62450Y-226343D01*
X62176Y-227004D01*
Y-227720D01*
X62450Y-228382D01*
X62957Y-228888D01*
X63618Y-229162D01*
X64334D01*
X64996Y-228888D01*
X65502Y-228382D01*
X65776Y-227720D01*
Y-227004D01*
X65502Y-226343D01*
X64996Y-225836D01*
X64334Y-225562D01*
D02*
G37*
G36*
X83035Y-230484D02*
X82319D01*
X81658Y-230757D01*
X81151Y-231264D01*
X80877Y-231925D01*
Y-232642D01*
X81151Y-233303D01*
X81658Y-233809D01*
X82319Y-234084D01*
X83035D01*
X83697Y-233809D01*
X84203Y-233303D01*
X84477Y-232642D01*
Y-231925D01*
X84203Y-231264D01*
X83697Y-230757D01*
X83035Y-230484D01*
D02*
G37*
G36*
X69256Y-283633D02*
X68540D01*
X67878Y-283907D01*
X67372Y-284414D01*
X67098Y-285075D01*
Y-285791D01*
X67372Y-286453D01*
X67878Y-286959D01*
X68540Y-287233D01*
X69256D01*
X69917Y-286959D01*
X70424Y-286453D01*
X70698Y-285791D01*
Y-285075D01*
X70424Y-284414D01*
X69917Y-283907D01*
X69256Y-283633D01*
D02*
G37*
G36*
X68271Y-338751D02*
X67555D01*
X66894Y-339025D01*
X66387Y-339532D01*
X66113Y-340193D01*
Y-340909D01*
X66387Y-341571D01*
X66894Y-342077D01*
X67555Y-342351D01*
X68271D01*
X68933Y-342077D01*
X69439Y-341571D01*
X69713Y-340909D01*
Y-340193D01*
X69439Y-339532D01*
X68933Y-339025D01*
X68271Y-338751D01*
D02*
G37*
G36*
X442287Y-121083D02*
X441571D01*
X440909Y-121358D01*
X440403Y-121864D01*
X440129Y-122525D01*
Y-123241D01*
X440403Y-123903D01*
X440909Y-124409D01*
X441571Y-124683D01*
X442287D01*
X442949Y-124409D01*
X443455Y-123903D01*
X443729Y-123241D01*
Y-122525D01*
X443455Y-121864D01*
X442949Y-121358D01*
X442287Y-121083D01*
D02*
G37*
G36*
X430850Y-134673D02*
X430134D01*
X429472Y-134947D01*
X428966Y-135453D01*
X428692Y-136115D01*
Y-136831D01*
X428966Y-137493D01*
X429472Y-137999D01*
X430134Y-138273D01*
X430850D01*
X431512Y-137999D01*
X432018Y-137493D01*
X432292Y-136831D01*
Y-136115D01*
X432018Y-135453D01*
X431512Y-134947D01*
X430850Y-134673D01*
D02*
G37*
G36*
X436972Y-134814D02*
X436256D01*
X435595Y-135088D01*
X435088Y-135595D01*
X434814Y-136256D01*
Y-136972D01*
X435088Y-137634D01*
X435595Y-138140D01*
X436256Y-138414D01*
X436972D01*
X437634Y-138140D01*
X438140Y-137634D01*
X438414Y-136972D01*
Y-136256D01*
X438140Y-135595D01*
X437634Y-135088D01*
X436972Y-134814D01*
D02*
G37*
G36*
X461677Y-141950D02*
X460961D01*
X460299Y-142224D01*
X459793Y-142730D01*
X459519Y-143392D01*
Y-144108D01*
X459793Y-144769D01*
X460299Y-145276D01*
X460961Y-145550D01*
X461677D01*
X462296Y-145293D01*
X462434Y-145366D01*
X462703Y-145619D01*
X462528Y-146039D01*
Y-146755D01*
X462803Y-147417D01*
X463309Y-147923D01*
X463970Y-148197D01*
X464686D01*
X465348Y-147923D01*
X465854Y-147417D01*
X466128Y-146755D01*
Y-146039D01*
X465854Y-145377D01*
X465348Y-144871D01*
X464686Y-144597D01*
X463970D01*
X463351Y-144853D01*
X463213Y-144781D01*
X462945Y-144528D01*
X463119Y-144108D01*
Y-143392D01*
X462845Y-142730D01*
X462338Y-142224D01*
X461677Y-141950D01*
D02*
G37*
G36*
X547602Y-155287D02*
X546886D01*
X546224Y-155561D01*
X545718Y-156067D01*
X545444Y-156729D01*
Y-157445D01*
X545718Y-158106D01*
X546224Y-158613D01*
X546886Y-158887D01*
X547602D01*
X548264Y-158613D01*
X548770Y-158106D01*
X549044Y-157445D01*
Y-156729D01*
X548770Y-156067D01*
X548264Y-155561D01*
X547602Y-155287D01*
D02*
G37*
G36*
X459677Y-156122D02*
X458961D01*
X458299Y-156396D01*
X457793Y-156903D01*
X457519Y-157564D01*
Y-158280D01*
X457793Y-158942D01*
X458299Y-159448D01*
X458961Y-159722D01*
X459677D01*
X460338Y-159448D01*
X460845Y-158942D01*
X461119Y-158280D01*
Y-157564D01*
X460845Y-156903D01*
X460338Y-156396D01*
X459677Y-156122D01*
D02*
G37*
G36*
X450161Y-156123D02*
X449445D01*
X448783Y-156397D01*
X448277Y-156903D01*
X448003Y-157565D01*
Y-158281D01*
X448277Y-158942D01*
X448783Y-159449D01*
X449445Y-159723D01*
X450161D01*
X450823Y-159449D01*
X451329Y-158942D01*
X451603Y-158281D01*
Y-157565D01*
X451329Y-156903D01*
X450823Y-156397D01*
X450161Y-156123D01*
D02*
G37*
G36*
X518695Y-157834D02*
X517979D01*
X517317Y-158108D01*
X516811Y-158614D01*
X516537Y-159276D01*
Y-159992D01*
X516811Y-160653D01*
X517317Y-161160D01*
X517979Y-161434D01*
X518695D01*
X519357Y-161160D01*
X519863Y-160653D01*
X520137Y-159992D01*
Y-159276D01*
X519863Y-158614D01*
X519357Y-158108D01*
X518695Y-157834D01*
D02*
G37*
G36*
X533696Y-148858D02*
X532335D01*
X531001Y-149124D01*
X529744Y-149644D01*
X528613Y-150400D01*
X527652Y-151362D01*
X526896Y-152493D01*
X526375Y-153750D01*
X526110Y-155084D01*
Y-156444D01*
X526375Y-157778D01*
X526896Y-159035D01*
X527652Y-160166D01*
X528613Y-161128D01*
X529744Y-161884D01*
X531001Y-162404D01*
X532335Y-162670D01*
X533696D01*
X535030Y-162404D01*
X536286Y-161884D01*
X537417Y-161128D01*
X538379Y-160166D01*
X539135Y-159035D01*
X539655Y-157778D01*
X539921Y-156444D01*
Y-155084D01*
X539655Y-153750D01*
X539135Y-152493D01*
X538379Y-151362D01*
X537417Y-150400D01*
X536286Y-149644D01*
X535030Y-149124D01*
X533696Y-148858D01*
D02*
G37*
G36*
X459677Y-160710D02*
X458961D01*
X458299Y-160985D01*
X457793Y-161491D01*
X457519Y-162152D01*
Y-162868D01*
X457793Y-163530D01*
X458299Y-164036D01*
X458961Y-164310D01*
X459677D01*
X460338Y-164036D01*
X460845Y-163530D01*
X461119Y-162868D01*
Y-162152D01*
X460845Y-161491D01*
X460338Y-160985D01*
X459677Y-160710D01*
D02*
G37*
G36*
X449866Y-160749D02*
X449150D01*
X448488Y-161023D01*
X447982Y-161529D01*
X447708Y-162191D01*
Y-162907D01*
X447982Y-163568D01*
X448488Y-164075D01*
X449150Y-164349D01*
X449866D01*
X450527Y-164075D01*
X451034Y-163568D01*
X451308Y-162907D01*
Y-162191D01*
X451034Y-161529D01*
X450527Y-161023D01*
X449866Y-160749D01*
D02*
G37*
G36*
X516060Y-161003D02*
X515344D01*
X514683Y-161277D01*
X514176Y-161783D01*
X513902Y-162445D01*
Y-163161D01*
X514176Y-163822D01*
X514683Y-164329D01*
X515344Y-164603D01*
X516060D01*
X516722Y-164329D01*
X517228Y-163822D01*
X517502Y-163161D01*
Y-162445D01*
X517228Y-161783D01*
X516722Y-161277D01*
X516060Y-161003D01*
D02*
G37*
G36*
X451208Y-172327D02*
X450492D01*
X449830Y-172601D01*
X449324Y-173107D01*
X449050Y-173769D01*
Y-174485D01*
X449324Y-175146D01*
X449830Y-175653D01*
X450492Y-175927D01*
X451208D01*
X451869Y-175653D01*
X452376Y-175146D01*
X452650Y-174485D01*
Y-173769D01*
X452376Y-173107D01*
X451869Y-172601D01*
X451208Y-172327D01*
D02*
G37*
G36*
X457642Y-173347D02*
X456925D01*
X456264Y-173621D01*
X455758Y-174128D01*
X455483Y-174789D01*
Y-175505D01*
X455758Y-176167D01*
X456264Y-176673D01*
X456925Y-176947D01*
X457642D01*
X458303Y-176673D01*
X458323Y-176654D01*
X458660Y-176467D01*
X459166Y-176974D01*
X459828Y-177248D01*
X460544D01*
X461206Y-176974D01*
X461712Y-176467D01*
X461986Y-175806D01*
Y-175090D01*
X461712Y-174428D01*
X461206Y-173922D01*
X460544Y-173648D01*
X459828D01*
X459166Y-173922D01*
X459147Y-173941D01*
X458809Y-174128D01*
X458303Y-173621D01*
X457642Y-173347D01*
D02*
G37*
G36*
X585004Y-176940D02*
X584288D01*
X583626Y-177214D01*
X583120Y-177720D01*
X582846Y-178382D01*
Y-179098D01*
X583120Y-179760D01*
X583626Y-180266D01*
X584288Y-180540D01*
X585004D01*
X585665Y-180266D01*
X586172Y-179760D01*
X586446Y-179098D01*
Y-178382D01*
X586172Y-177720D01*
X585665Y-177214D01*
X585004Y-176940D01*
D02*
G37*
G36*
X599922Y-177140D02*
X599206D01*
X598545Y-177414D01*
X598038Y-177920D01*
X597764Y-178582D01*
Y-179298D01*
X598038Y-179960D01*
X598545Y-180466D01*
X599206Y-180740D01*
X599922D01*
X600584Y-180466D01*
X601090Y-179960D01*
X601364Y-179298D01*
Y-178582D01*
X601090Y-177920D01*
X600584Y-177414D01*
X599922Y-177140D01*
D02*
G37*
G36*
X595240Y-177334D02*
X594524D01*
X593862Y-177608D01*
X593356Y-178114D01*
X593082Y-178776D01*
Y-179492D01*
X593356Y-180154D01*
X593862Y-180660D01*
X594524Y-180934D01*
X595240D01*
X595901Y-180660D01*
X596408Y-180154D01*
X596682Y-179492D01*
Y-178776D01*
X596408Y-178114D01*
X595901Y-177608D01*
X595240Y-177334D01*
D02*
G37*
G36*
X590122D02*
X589406D01*
X588744Y-177608D01*
X588238Y-178114D01*
X587964Y-178776D01*
Y-179492D01*
X588238Y-180154D01*
X588744Y-180660D01*
X589406Y-180934D01*
X590122D01*
X590783Y-180660D01*
X591290Y-180154D01*
X591564Y-179492D01*
Y-178776D01*
X591290Y-178114D01*
X590783Y-177608D01*
X590122Y-177334D01*
D02*
G37*
G36*
X681854Y-177728D02*
X681138D01*
X680476Y-178002D01*
X679970Y-178508D01*
X679696Y-179169D01*
Y-179886D01*
X679970Y-180547D01*
X680476Y-181053D01*
X681138Y-181328D01*
X681854D01*
X682516Y-181053D01*
X683022Y-180547D01*
X683296Y-179886D01*
Y-179169D01*
X683022Y-178508D01*
X682516Y-178002D01*
X681854Y-177728D01*
D02*
G37*
G36*
X499177Y-182058D02*
X498461D01*
X497799Y-182332D01*
X497293Y-182839D01*
X497019Y-183500D01*
Y-184216D01*
X497293Y-184878D01*
X497799Y-185384D01*
X498461Y-185658D01*
X499177D01*
X499838Y-185384D01*
X500345Y-184878D01*
X500619Y-184216D01*
Y-183500D01*
X500345Y-182839D01*
X499838Y-182332D01*
X499177Y-182058D01*
D02*
G37*
G36*
X635791Y-182452D02*
X635075D01*
X634413Y-182726D01*
X633907Y-183232D01*
X633633Y-183894D01*
Y-184610D01*
X633907Y-185272D01*
X634413Y-185778D01*
X634577Y-185846D01*
X634604Y-185895D01*
X634657Y-186420D01*
X634301Y-186776D01*
X634027Y-187437D01*
Y-188153D01*
X634301Y-188815D01*
X634807Y-189321D01*
X635469Y-189595D01*
X636185D01*
X636846Y-189321D01*
X637353Y-188815D01*
X637627Y-188153D01*
Y-187437D01*
X637353Y-186776D01*
X636846Y-186269D01*
X636683Y-186201D01*
X636656Y-186153D01*
X636603Y-185627D01*
X636959Y-185272D01*
X637233Y-184610D01*
Y-183894D01*
X636959Y-183232D01*
X636453Y-182726D01*
X635791Y-182452D01*
D02*
G37*
G36*
X499051Y-186551D02*
X498335D01*
X497673Y-186825D01*
X497167Y-187331D01*
X496893Y-187993D01*
Y-188709D01*
X497167Y-189370D01*
X497673Y-189877D01*
X498335Y-190151D01*
X499051D01*
X499713Y-189877D01*
X500219Y-189370D01*
X500493Y-188709D01*
Y-187993D01*
X500219Y-187331D01*
X499713Y-186825D01*
X499051Y-186551D01*
D02*
G37*
G36*
X528810Y-192597D02*
X527981D01*
X527215Y-192914D01*
X526629Y-193500D01*
X526312Y-194265D01*
Y-195094D01*
X526629Y-195860D01*
X527215Y-196446D01*
X527981Y-196763D01*
X528810D01*
X529575Y-196446D01*
X530161Y-195860D01*
X530478Y-195094D01*
Y-194265D01*
X530161Y-193500D01*
X529575Y-192914D01*
X528810Y-192597D01*
D02*
G37*
G36*
X531854Y-201792D02*
X531138D01*
X530477Y-202066D01*
X529970Y-202572D01*
X529696Y-203234D01*
Y-203950D01*
X529970Y-204612D01*
X530477Y-205118D01*
X531138Y-205392D01*
X531854D01*
X532516Y-205118D01*
X533022Y-204612D01*
X533296Y-203950D01*
Y-203234D01*
X533022Y-202572D01*
X532516Y-202066D01*
X531854Y-201792D01*
D02*
G37*
G36*
X525949D02*
X525233D01*
X524571Y-202066D01*
X524065Y-202572D01*
X523791Y-203234D01*
Y-203950D01*
X524065Y-204612D01*
X524571Y-205118D01*
X525233Y-205392D01*
X525949D01*
X526610Y-205118D01*
X527116Y-204612D01*
X527391Y-203950D01*
Y-203234D01*
X527116Y-202572D01*
X526610Y-202066D01*
X525949Y-201792D01*
D02*
G37*
G36*
X592913Y-223228D02*
X570079D01*
Y-244882D01*
X592913D01*
Y-223228D01*
D02*
G37*
%LPD*%
D14*
X579528Y-268504D02*
Y-266535D01*
X571260Y-276772D02*
X579528Y-268504D01*
X559842Y-276772D02*
X571260D01*
X549178Y-287437D02*
X559842Y-276772D01*
X544909Y-287437D02*
X549178D01*
X30512Y-170276D02*
X64370D01*
X64567Y-170079D01*
X63779Y-283465D02*
X64961Y-282283D01*
X26575Y-283465D02*
X63779D01*
X-23622Y-346457D02*
X67323D01*
X-23622Y-294291D02*
X66069D01*
X63189Y-241142D02*
X63324Y-241007D01*
X-23622Y-241142D02*
X63189D01*
X-23622Y-70866D02*
X31496D01*
X33465Y-68898D01*
X-23622Y-114173D02*
X31496D01*
X33465Y-116142D01*
X-23622Y-187992D02*
X67323D01*
X356578Y-225247D02*
X356641Y-225183D01*
Y-222766D01*
X352379Y-218504D02*
X356641Y-222766D01*
X123031Y-218504D02*
X352379D01*
X115157Y-226378D02*
X123031Y-218504D01*
X115157Y-315945D02*
Y-226378D01*
X101378Y-329724D02*
X115157Y-315945D01*
X87598Y-329724D02*
X101378D01*
D19*
X318358Y-352534D02*
G03*
X318858Y-353034I500J0D01*
G01*
X318358Y-352534D02*
G03*
X317358Y-352534I-500J0D01*
G01*
X316358Y-352634D02*
G03*
X317358Y-352634I500J0D01*
G01*
X316358Y-352313D02*
G03*
X315358Y-352313I-500J0D01*
G01*
X314358Y-352634D02*
G03*
X315358Y-352634I500J0D01*
G01*
X314358Y-352286D02*
G03*
X313358Y-352286I-500J0D01*
G01*
X312358Y-352634D02*
G03*
X313358Y-352634I500J0D01*
G01*
X312358Y-352286D02*
G03*
X311358Y-352286I-500J0D01*
G01*
X310858Y-353034D02*
G03*
X311358Y-352534I0J500D01*
G01*
X227373Y-351990D02*
G03*
X227373Y-353050I530J-530D01*
G01*
X227473Y-354211D02*
G03*
X227473Y-353150I-530J530D01*
G01*
X226412Y-354211D02*
G03*
X227473Y-354211I530J530D01*
G01*
X226281Y-354080D02*
G03*
X225221Y-354080I-530J-530D01*
G01*
D02*
G03*
X225221Y-355141I530J-530D01*
G01*
X225352Y-356332D02*
G03*
X225352Y-355271I-530J530D01*
G01*
X224291Y-356332D02*
G03*
X225352Y-356332I530J530D01*
G01*
X224160Y-356201D02*
G03*
X223099Y-356201I-530J-530D01*
G01*
D02*
G03*
X223099Y-357262I530J-530D01*
G01*
X223230Y-358453D02*
G03*
X223230Y-357393I-530J530D01*
G01*
X222170Y-358453D02*
G03*
X223230Y-358453I530J530D01*
G01*
X222070Y-358354D02*
G03*
X221009Y-358354I-530J-530D01*
G01*
X216986Y-362377D02*
G03*
X214518Y-366447I7071J-7071D01*
G01*
D02*
G03*
X214057Y-369448I9539J-3002D01*
G01*
X431637Y-327573D02*
G03*
X431930Y-326866I-707J707D01*
G01*
X432417Y-328349D02*
G03*
X433030Y-326869I-1480J1480D01*
G01*
X447244Y-324867D02*
G03*
X446416Y-326866I1999J-1999D01*
G01*
X225005Y-380873D02*
G03*
X225774Y-380554I0J1088D01*
G01*
X234076Y-353732D02*
G03*
X232127Y-358436I4704J-4704D01*
G01*
X460630Y-324852D02*
G03*
X459605Y-327326I2474J-2474D01*
G01*
X252650Y-372202D02*
G03*
X251793Y-374451I2117J-2094D01*
G01*
X431930Y-326866D02*
G03*
X431102Y-324867I-2827J0D01*
G01*
X433858Y-324867D02*
G03*
X433030Y-326866I1999J-1999D01*
G01*
X445316D02*
G03*
X444488Y-324867I-2827J0D01*
G01*
X458505Y-327326D02*
G03*
X457480Y-324852I-3499J0D01*
G01*
X465308Y-345322D02*
G03*
X465453Y-344970I-355J352D01*
G01*
X464859Y-345771D02*
G03*
X464862Y-345768I-351J356D01*
G01*
X466088Y-346098D02*
G03*
X466553Y-344970I-1135J1128D01*
G01*
X465959Y-346227D02*
G03*
X465962Y-346223I-353J355D01*
G01*
X466553Y-326098D02*
G03*
X464280Y-320992I-6872J0D01*
G01*
X450943Y-354134D02*
G03*
X462145Y-350041I1197J14098D01*
G01*
X450943Y-353034D02*
G03*
X461347Y-349283I1212J12943D01*
G01*
X465453Y-325914D02*
G03*
X463902Y-322169I-5295J-0D01*
G01*
X423940Y-332023D02*
G03*
X426257Y-326436I-5579J5587D01*
G01*
X424435Y-333084D02*
G03*
X427357Y-326029I-7055J7055D01*
G01*
X426402Y-323795D02*
G03*
X426257Y-324462I1454J-667D01*
G01*
X419657Y-334806D02*
G03*
X422217Y-333746I0J3621D01*
G01*
X427501Y-324110D02*
G03*
X427357Y-324462I355J-352D01*
G01*
X431112Y-320706D02*
G03*
X430760Y-320851I0J-500D01*
G01*
X431112Y-319606D02*
G03*
X430445Y-319752I0J-1600D01*
G01*
X212402Y-378583D02*
G03*
X212652Y-378738I4030J6227D01*
G01*
X214258Y-379178D02*
G03*
X215206Y-378455I198J723D01*
G01*
X216706Y-377977D02*
G03*
X215206Y-377977I-750J0D01*
G01*
X216706Y-379023D02*
G03*
X217456Y-379773I750J0D01*
G01*
X229198Y-375575D02*
G03*
X232127Y-368504I-7071J7071D01*
G01*
X210273Y-374722D02*
G03*
X210433Y-374655I0J227D01*
G01*
X209515Y-374722D02*
G03*
X209161Y-374868I0J-500D01*
G01*
X209161Y-374868D02*
G03*
X209015Y-375221I353J-353D01*
G01*
X209015D02*
G03*
X209161Y-375575I500J0D01*
G01*
X254893Y-337506D02*
G03*
X247054Y-340754I0J-11087D01*
G01*
X417562Y-337506D02*
G03*
X424633Y-334577I0J10000D01*
G01*
X211187Y-377601D02*
G03*
X212402Y-378583I5244J5244D01*
G01*
X229980Y-376349D02*
G03*
X233227Y-368509I-7840J7840D01*
G01*
X207915Y-375221D02*
G03*
X207768Y-374868I-500J0D01*
G01*
D02*
G03*
X207415Y-374722I-354J-354D01*
G01*
X207915Y-375449D02*
G03*
X208222Y-376192I1050J0D01*
G01*
X206496Y-374655D02*
G03*
X206656Y-374722I160J160D01*
G01*
X210420Y-378390D02*
G03*
X216416Y-380873I5996J5996D01*
G01*
X234857Y-354506D02*
G03*
X233227Y-358440I3934J-3934D01*
G01*
X254899Y-338606D02*
G03*
X247828Y-341535I0J-10000D01*
G01*
X417567Y-338606D02*
G03*
X425407Y-335359I0J11087D01*
G01*
X221108Y-376185D02*
G03*
X222638Y-374655I0J1530D01*
G01*
X440198Y-308324D02*
G03*
X439675Y-307062I-1785J0D01*
G01*
X217904Y-376102D02*
G03*
X217520Y-375984I-384J-568D01*
G01*
X215717Y-375322D02*
G03*
X217308Y-375984I1590J1576D01*
G01*
X217904Y-376102D02*
G03*
X218177Y-376185I276J417D01*
G01*
X439675Y-309586D02*
G03*
X440198Y-308324I-1262J1262D01*
G01*
X247593Y-334806D02*
G03*
X239754Y-338054I0J-11087D01*
G01*
X212957Y-371682D02*
G03*
X213579Y-373184I2124J0D01*
G01*
X436057Y-319606D02*
G03*
X436679Y-319349I0J880D01*
G01*
X439675Y-309586D02*
G03*
X439221Y-310682I1096J-1096D01*
G01*
X216204Y-361603D02*
G03*
X212957Y-369443I7840J-7840D01*
G01*
X217251Y-374601D02*
G03*
X218420Y-374116I0J1654D01*
G01*
X216056Y-374106D02*
G03*
X217251Y-374601I1194J1194D01*
G01*
X419661Y-335906D02*
G03*
X422993Y-334526I0J4712D01*
G01*
X247599Y-335906D02*
G03*
X240528Y-338835I0J-10000D01*
G01*
X214057Y-371682D02*
G03*
X214357Y-372406I1024J0D01*
G01*
X441982Y-306901D02*
G03*
X441298Y-308552I1651J-1651D01*
G01*
X440614Y-310203D02*
G03*
X441298Y-308552I-1651J1651D01*
G01*
X436062Y-320706D02*
G03*
X437453Y-320130I0J1967D01*
G01*
X440614Y-310203D02*
G03*
X440321Y-310910I707J-707D01*
G01*
X440001Y-317582D02*
G03*
X440321Y-316809I-773J773D01*
G01*
X437545Y-341806D02*
G03*
X442857Y-339606I0J7511D01*
G01*
X262949Y-341806D02*
G03*
X255109Y-345054I0J-11087D01*
G01*
X437549Y-342906D02*
G03*
X443632Y-340387I0J8602D01*
G01*
X262954Y-342906D02*
G03*
X255883Y-345835I0J-10000D01*
G01*
X249542Y-352177D02*
G03*
X246613Y-359248I7071J-7071D01*
G01*
X248762Y-351401D02*
G03*
X245513Y-359244I7842J-7842D01*
G01*
X453937Y-311649D02*
G03*
X454233Y-312359I1000J0D01*
G01*
X454329Y-312476D02*
G03*
X454256Y-312382I-428J-258D01*
G01*
X454329Y-312476D02*
G03*
X454375Y-312551I2388J1423D01*
G01*
D02*
G03*
X454751Y-313019I2342J1498D01*
G01*
X454937Y-311442D02*
G03*
X455085Y-311797I500J0D01*
G01*
X283172Y-353034D02*
G03*
X275332Y-356281I0J-11087D01*
G01*
X273719Y-357894D02*
G03*
X270914Y-364667I6773J-6773D01*
G01*
X269813Y-374162D02*
G03*
X270914Y-371505I-2657J2657D01*
G01*
X269502Y-374291D02*
G03*
X269813Y-374162I0J440D01*
G01*
X455069Y-307800D02*
G03*
X454937Y-308136I368J-339D01*
G01*
X283178Y-354134D02*
G03*
X276107Y-357063I0J-10000D01*
G01*
X274508Y-358661D02*
G03*
X272014Y-364683I6021J-6021D01*
G01*
Y-371248D02*
G03*
X273296Y-374344I4379J0D01*
G01*
X273425Y-374655D02*
G03*
X273296Y-374344I-440J0D01*
G01*
X455069Y-307800D02*
G03*
X452387Y-306744I-1132J1058D01*
G01*
X451536Y-307097D02*
G03*
X452387Y-306744I351J356D01*
G01*
X244966Y-375972D02*
G03*
X246613Y-372971I-1910J3001D01*
G01*
X238607Y-375270D02*
G03*
X244966Y-375972I3616J3608D01*
G01*
X443645Y-340373D02*
G03*
X446416Y-333684I-6690J6690D01*
G01*
X241929Y-374655D02*
G03*
X244862Y-374595I1438J1455D01*
G01*
X244994Y-374439D02*
G03*
X245061Y-374345I-2061J1552D01*
G01*
X244763Y-363361D02*
G03*
X245513Y-362611I0J750D01*
G01*
X244863Y-366361D02*
G03*
X244863Y-364861I0J750D01*
G01*
Y-369361D02*
G03*
X244863Y-367861I0J750D01*
G01*
X244561Y-363361D02*
G03*
X244561Y-364861I0J-750D01*
G01*
X244763Y-369361D02*
G03*
X244763Y-370861I0J-750D01*
G01*
X244678Y-366361D02*
G03*
X244678Y-367861I0J-750D01*
G01*
X245513Y-371611D02*
G03*
X244763Y-370861I-750J0D01*
G01*
X244862Y-374595D02*
G03*
X244992Y-374441I-1496J1395D01*
G01*
X442857Y-339606D02*
G03*
X445316Y-333669I-5938J5938D01*
G01*
X445220Y-347806D02*
G03*
X453060Y-344559I0J11087D01*
G01*
X274699Y-347806D02*
G03*
X267628Y-350735I0J-10000D01*
G01*
X259729Y-364111D02*
G03*
X259802Y-364289I251J0D01*
G01*
X262657Y-355706D02*
G03*
X259729Y-362777I7071J-7071D01*
G01*
X259655Y-367004D02*
G03*
X259653Y-367007I351J-356D01*
G01*
X456364Y-341254D02*
G03*
X459605Y-333431I-7823J7823D01*
G01*
X445215Y-346706D02*
G03*
X452286Y-343777I0J10000D01*
G01*
X274693Y-346706D02*
G03*
X266854Y-349954I0J-11087D01*
G01*
X258555Y-366297D02*
G03*
X258629Y-366120I-178J178D01*
G01*
X256382Y-374866D02*
G03*
X256890Y-374655I0J719D01*
G01*
X256258Y-374866D02*
G03*
X255841Y-375038I0J-590D01*
G01*
Y-375039D02*
G03*
X255668Y-375456I417J-417D01*
G01*
X251794Y-374454D02*
G03*
X252426Y-375861I2176J133D01*
G01*
X252429Y-375863D02*
G03*
X255508Y-375906I1562J1586D01*
G01*
X455576Y-340487D02*
G03*
X458505Y-333416I-7071J7071D01*
G01*
X259655Y-367004D02*
G03*
X259802Y-366651I-353J354D01*
G01*
X259791Y-369795D02*
G03*
X259791Y-368734I-530J530D01*
G01*
X259389Y-367271D02*
G03*
X259389Y-368332I530J-530D01*
G01*
X258131Y-369196D02*
G03*
X257070Y-369196I-530J-530D01*
G01*
X258730Y-369795D02*
G03*
X259791Y-369795I530J530D01*
G01*
X257669Y-371916D02*
G03*
X257669Y-370855I-530J530D01*
G01*
X256609Y-371916D02*
G03*
X257669Y-371916I530J530D01*
G01*
X257070Y-369196D02*
G03*
X257070Y-370256I530J-530D01*
G01*
X256207Y-371514D02*
G03*
X255146Y-371514I-530J-530D01*
G01*
X261876Y-354932D02*
G03*
X258629Y-362771I7840J-7840D01*
G01*
X255508Y-375906D02*
G03*
X255668Y-375539I-340J367D01*
G01*
X318858Y-353034D02*
X321782D01*
X318358Y-352534D02*
Y-352534D01*
X317358Y-352634D02*
Y-352534D01*
X316358Y-352634D02*
Y-352313D01*
X315358Y-352634D02*
Y-352313D01*
X314358Y-352634D02*
Y-352286D01*
X313358Y-352634D02*
Y-352286D01*
X312358Y-352634D02*
Y-352286D01*
X311358Y-352534D02*
Y-352286D01*
X310608Y-353034D02*
X310858D01*
X321782D02*
X450943D01*
X283172D02*
X310608D01*
X227373Y-351990D02*
X232522Y-346841D01*
X227373Y-353050D02*
X227373Y-353050D01*
X227473Y-353150D01*
X226281Y-354080D02*
X226412Y-354211D01*
X225221Y-355141D02*
X225352Y-355271D01*
X224160Y-356201D02*
X224291Y-356332D01*
X223099Y-357262D02*
X223230Y-357393D01*
X222070Y-358354D02*
X222170Y-358453D01*
X219772Y-359591D02*
X221009Y-358354D01*
X232522Y-346841D02*
X240528Y-338835D01*
X216986Y-362377D02*
X219772Y-359591D01*
X247599Y-335906D02*
X419661D01*
X216208Y-361599D02*
X239691Y-338116D01*
X216204Y-361603D02*
X216208Y-361599D01*
X239691Y-338116D02*
X239754Y-338054D01*
X252650Y-372202D02*
X252652Y-372200D01*
X433030Y-326869D02*
Y-326866D01*
X459605Y-333431D02*
Y-327326D01*
X446416Y-333684D02*
Y-326866D01*
X445316Y-333669D02*
Y-326866D01*
X225774Y-380554D02*
X229980Y-376349D01*
X424633Y-334577D02*
X431637Y-327573D01*
X238607Y-375270D02*
X238607Y-375270D01*
X232127Y-368504D02*
Y-358436D01*
X460630Y-324852D02*
X460630Y-324852D01*
X433858Y-324867D02*
Y-324867D01*
X458505Y-333416D02*
Y-327326D01*
X447244Y-324867D02*
Y-324852D01*
X234076Y-353732D02*
X247054Y-340754D01*
X251793Y-374451D02*
X251794Y-374454D01*
X431102Y-324867D02*
Y-324852D01*
X433858Y-324867D02*
X433858Y-324867D01*
X433858Y-324867D02*
Y-324852D01*
X444488Y-324867D02*
Y-324852D01*
X466553Y-344970D02*
Y-326098D01*
X465453Y-344970D02*
Y-325914D01*
X464862Y-345768D02*
X465308Y-345322D01*
X462145Y-350041D02*
X465959Y-346227D01*
X465962Y-346223D02*
X466088Y-346098D01*
X461347Y-349283D02*
X464859Y-345771D01*
X454751Y-313019D02*
X463902Y-322169D01*
X348622Y-354134D02*
X450943D01*
X426257Y-326436D02*
Y-324462D01*
X422217Y-333746D02*
X423940Y-332023D01*
X426402Y-323795D02*
X430445Y-319752D01*
X427501Y-324110D02*
X430760Y-320851D01*
X427357Y-326029D02*
Y-324462D01*
X431112Y-319606D02*
X436057D01*
X431112Y-320706D02*
X436062D01*
X212402Y-378583D02*
X212402Y-378583D01*
X212652Y-378738D02*
X214258Y-379178D01*
X214258Y-379178D02*
X214258Y-379178D01*
X215206Y-378455D02*
Y-377977D01*
X216706Y-379023D02*
Y-377977D01*
X217456Y-379773D02*
X219207D01*
X219207D01*
X219207D02*
X225000Y-379773D01*
X229198Y-375575D01*
X209515Y-374722D02*
X210273D01*
X209161Y-375575D02*
X211187Y-377601D01*
X209015Y-375221D02*
X209015D01*
X254893Y-337506D02*
X417562D01*
X207915Y-375449D02*
Y-375221D01*
X206656Y-374722D02*
X207415D01*
X216416Y-380873D02*
X225005D01*
X233227Y-368509D02*
Y-358440D01*
X234857Y-354506D02*
X247828Y-341535D01*
X254899Y-338606D02*
X417567D01*
X425407Y-335359D02*
X432417Y-328349D01*
X208222Y-376192D02*
X210420Y-378390D01*
X219285Y-376185D02*
X221108D01*
X213579Y-373184D02*
X213579Y-373184D01*
X214479Y-374084D01*
X218177Y-376185D02*
X219280D01*
X440198Y-308324D02*
X440198D01*
X217308Y-375984D02*
X217520Y-375984D01*
X214479Y-374084D02*
X215717Y-375322D01*
X219280Y-376185D02*
X219285Y-376185D01*
X439370Y-306757D02*
X439675Y-307062D01*
X247593Y-334806D02*
X419657D01*
X212957Y-371682D02*
Y-369443D01*
X436679Y-319349D02*
X439221Y-316806D01*
X436679Y-319349D02*
X436679Y-319349D01*
X439221Y-316806D02*
Y-310682D01*
X439370Y-306757D02*
Y-306742D01*
X214357Y-372406D02*
X216056Y-374106D01*
X422993Y-334526D02*
X424435Y-333084D01*
X218420Y-374116D02*
X218444Y-374109D01*
X218445Y-374108D01*
X214057Y-371682D02*
Y-369448D01*
X441982Y-306901D02*
X442126Y-306757D01*
X437453Y-320130D02*
X440001Y-317582D01*
X440321Y-316809D02*
Y-310910D01*
X442126Y-306757D02*
Y-306742D01*
X262949Y-341806D02*
X437545D01*
X262954Y-342906D02*
X437549D01*
X246613Y-372967D02*
Y-359248D01*
X245513Y-360861D02*
Y-359244D01*
X249542Y-352177D02*
X255883Y-345835D01*
X248762Y-351401D02*
X255109Y-345054D01*
X283178Y-354134D02*
X348622D01*
X453937Y-311649D02*
Y-306742D01*
X454937Y-311442D02*
Y-308136D01*
X454233Y-312359D02*
X454256Y-312382D01*
X455085Y-311797D02*
X464280Y-320992D01*
X270914Y-371120D02*
Y-364815D01*
X272014Y-371120D02*
Y-364815D01*
X270914Y-371505D02*
Y-371120D01*
X272014Y-371248D02*
Y-371120D01*
X270914Y-364815D02*
Y-364667D01*
X272014Y-364815D02*
Y-364683D01*
X274508Y-358661D02*
X276107Y-357063D01*
X451181Y-306742D02*
X451536Y-307097D01*
X273719Y-357894D02*
X275332Y-356281D01*
X246613Y-372971D02*
X246613Y-372967D01*
X443632Y-340387D02*
X443645Y-340373D01*
X241929Y-374655D02*
X241929Y-374655D01*
X237992D02*
X238607Y-375270D01*
X245513Y-362611D02*
Y-360861D01*
Y-372887D02*
Y-371611D01*
X245061Y-374345D02*
X245513Y-372887D01*
X244678Y-366361D02*
X244863D01*
X244763Y-369361D02*
X244863D01*
X244678Y-367861D02*
X244863D01*
X244561Y-363361D02*
X244763D01*
X244561Y-364861D02*
X244863D01*
X244992Y-374441D02*
X244994Y-374439D01*
X244763Y-370861D02*
X244763D01*
X274699Y-347806D02*
X445220D01*
X262657Y-355706D02*
X267628Y-350735D01*
X259802Y-366651D02*
Y-364289D01*
X259729Y-364111D02*
Y-362777D01*
X259565Y-367094D02*
X259653Y-367007D01*
X453060Y-344559D02*
X456364Y-341254D01*
X274693Y-346706D02*
X445215D01*
X258555Y-366297D02*
X258555Y-366297D01*
X256258Y-374866D02*
X256382D01*
X255668Y-375539D02*
Y-375456D01*
X252426Y-375861D02*
X252429Y-375863D01*
X452286Y-343777D02*
X455576Y-340487D01*
X259389Y-368332D02*
X259791Y-368734D01*
X259565Y-367094D02*
X259565Y-367094D01*
X259389Y-367271D02*
X259565Y-367094D01*
X259389Y-367271D02*
X259389Y-367271D01*
X258131Y-369196D02*
X258730Y-369795D01*
X257070Y-370256D02*
X257669Y-370855D01*
X256207Y-371514D02*
X256609Y-371916D01*
X253201Y-373459D02*
X255146Y-371514D01*
X253089Y-373994D02*
X253201Y-373459D01*
X253625Y-374431D02*
X253635Y-374421D01*
X253655D01*
X253431Y-374431D02*
X253625D01*
X253120Y-374075D02*
X253307Y-374555D01*
X253431Y-374431D01*
X253089Y-373994D02*
X253120Y-374075D01*
X261876Y-354932D02*
X266854Y-349954D01*
X258629Y-366120D02*
Y-362771D01*
X252652Y-372200D02*
X258555Y-366297D01*
D24*
X680315Y-217323D02*
X681102Y-216535D01*
Y-215748D01*
X678346D02*
X681102D01*
X680315Y-272047D02*
Y-217323D01*
X668110Y-225984D02*
X678346Y-215748D01*
X683205Y-208796D02*
X686614Y-212205D01*
X673094Y-208796D02*
X683205D01*
X666929Y-222441D02*
X671302Y-218068D01*
X646850Y-222441D02*
X666929D01*
X671654Y-210236D02*
Y-208796D01*
Y-217323D02*
Y-210236D01*
Y-208796D02*
X673094D01*
X625000Y-48080D02*
Y-29773D01*
X442126Y-173277D02*
X443898Y-175049D01*
X416634Y-130659D02*
X442126Y-156151D01*
Y-173277D02*
Y-156151D01*
X436024Y-107037D02*
X473228Y-144242D01*
Y-171309D02*
Y-144242D01*
X469390Y-175147D02*
X473228Y-171309D01*
X476945Y-173228D02*
X486221D01*
X553103Y-147638D02*
X581102D01*
X485827Y-176378D02*
X519685Y-142520D01*
X541339D01*
X542126Y-141732D01*
X547198D01*
X553103Y-147638D01*
X614631Y-190222D02*
X646850Y-222441D01*
X565418Y-190222D02*
X614631D01*
X548184Y-172987D02*
X565418Y-190222D01*
X530027Y-172987D02*
X548184D01*
X604481Y-191882D02*
X638583Y-225984D01*
X564717Y-191882D02*
X604481D01*
X549060Y-176225D02*
X564717Y-191882D01*
X533044Y-176225D02*
X549060D01*
X576378Y-265354D02*
X576772Y-264961D01*
X576378Y-266142D02*
Y-265354D01*
X567323Y-275197D02*
X576378Y-266142D01*
X545276Y-275197D02*
X567323D01*
X553543Y-212205D02*
X590945D01*
X549213Y-207874D02*
X553543Y-212205D01*
X251575Y-122047D02*
X255118Y-118504D01*
X251575Y-128347D02*
Y-122047D01*
Y-128347D02*
X260236Y-137008D01*
X277165D01*
X282131Y-132042D01*
X412800D01*
X235433Y-118898D02*
X238189Y-116142D01*
X235433Y-128740D02*
Y-118898D01*
Y-128740D02*
X248425Y-141732D01*
X370472D01*
X378346Y-149606D01*
X417717D01*
X420866Y-152756D01*
X429134D01*
X433858Y-157480D01*
Y-175246D02*
Y-157480D01*
X486221Y-173228D02*
X521260Y-138189D01*
X545669D01*
X553150Y-145669D01*
X580315D01*
X614961Y-111024D01*
Y-98032D01*
X618898Y-94095D01*
Y-82284D01*
X620959Y-107781D02*
Y-100047D01*
X581102Y-147638D02*
X620959Y-107781D01*
X474016Y-176378D02*
X485827D01*
X638583Y-225984D02*
X668110D01*
X686614Y-215748D02*
Y-212205D01*
X682283Y-220079D02*
X686614Y-215748D01*
X682283Y-293307D02*
Y-220079D01*
X678346Y-297244D02*
X682283Y-293307D01*
X678441Y-273922D02*
X680315Y-272047D01*
X678441Y-292586D02*
Y-273922D01*
X675224Y-289370D02*
X678441Y-292586D01*
X538189Y-289370D02*
X675224D01*
X522441Y-273622D02*
X538189Y-289370D01*
X522441Y-273622D02*
Y-244882D01*
X500394Y-222835D02*
X522441Y-244882D01*
X675197Y-300394D02*
X678346Y-297244D01*
X546457Y-300394D02*
X675197D01*
X517323Y-271260D02*
X546457Y-300394D01*
X517323Y-271260D02*
Y-243701D01*
X495669Y-222047D02*
X517323Y-243701D01*
X271654Y-122835D02*
X272835Y-124016D01*
Y-128395D02*
Y-124016D01*
X505905Y-123622D02*
Y-111072D01*
X395423Y-108809D02*
X434252D01*
X290158D02*
X363902D01*
X371530Y-101181D01*
X387795D01*
X395423Y-108809D01*
X398220Y-107037D02*
X436024D01*
X290846D02*
X357079D01*
X367266Y-96850D01*
X388033D01*
X398220Y-107037D01*
X291339Y-281102D02*
X366142D01*
X270472Y-301969D02*
X291339Y-281102D01*
X270472Y-327165D02*
Y-301969D01*
X83465Y-167251D02*
X88117Y-162598D01*
X83465Y-211616D02*
Y-167251D01*
Y-211616D02*
X85431Y-213583D01*
X178083Y-162598D02*
X186863Y-153818D01*
X88117Y-162598D02*
X178083D01*
X177953Y-164567D02*
X187402Y-155118D01*
X87567Y-165542D02*
X88542Y-164567D01*
X177953D01*
X87567Y-165761D02*
Y-165542D01*
X142520Y-156693D02*
Y-155512D01*
X154724Y-143307D01*
X173622D01*
X180315Y-150000D01*
X291732D01*
X423461Y-178869D02*
X424213Y-178117D01*
X123739Y-259726D02*
X353251D01*
X120079Y-263386D02*
X123739Y-259726D01*
X416835Y-196581D02*
X416929Y-196675D01*
Y-237008D02*
Y-196675D01*
X411811Y-235433D02*
Y-196850D01*
X366142Y-281102D02*
X411811Y-235433D01*
X367717Y-286221D02*
X416929Y-237008D01*
X323228Y-286221D02*
X367717D01*
X282283Y-327165D02*
X323228Y-286221D01*
X430807Y-244390D02*
Y-175344D01*
X348031Y-327165D02*
X430807Y-244390D01*
X294094Y-327165D02*
X348031D01*
X424213Y-178117D02*
Y-173425D01*
X418110Y-167323D02*
X424213Y-173425D01*
X418110Y-167323D02*
Y-153648D01*
X416796Y-152333D02*
X418110Y-153648D01*
X376349Y-152333D02*
X416796D01*
X369685Y-145669D02*
X376349Y-152333D01*
X296063Y-145669D02*
X369685D01*
X291732Y-150000D02*
X296063Y-145669D01*
X327953Y-165354D02*
X402559D01*
X187402Y-155118D02*
X295276D01*
X312992Y-150394D02*
X327953Y-165354D01*
X300000Y-150394D02*
X312992D01*
X295276Y-155118D02*
X300000Y-150394D01*
X360236Y-162870D02*
X392434D01*
X186863Y-153818D02*
X293426D01*
X345398Y-148031D02*
X360236Y-162870D01*
X299213Y-148031D02*
X345398D01*
X293426Y-153818D02*
X299213Y-148031D01*
X412800Y-132042D02*
X437697Y-156939D01*
X65945Y-61860D02*
Y-57923D01*
X81880Y-324990D02*
Y-287582D01*
X359993Y-252984D02*
X360204D01*
X353251Y-259726D02*
X359993Y-252984D01*
X47244Y15748D02*
Y19685D01*
X40354Y16732D02*
X41339Y15748D01*
X40354Y16732D02*
Y19685D01*
X33465Y15748D02*
Y19833D01*
X26575Y16732D02*
Y19685D01*
X414370Y-169291D02*
X415596Y-170518D01*
X414370Y-169291D02*
Y-157480D01*
X415596Y-178762D02*
Y-170518D01*
X415670Y-168623D02*
X419596Y-172549D01*
Y-178439D02*
Y-172549D01*
X415670Y-168623D02*
Y-156942D01*
X417596Y-178600D02*
Y-175197D01*
X358592Y-239805D02*
X363672D01*
X354452Y-235453D02*
X354852Y-235853D01*
X354452Y-235453D02*
Y-235236D01*
X354541Y-223636D02*
Y-223636D01*
X354852Y-236065D02*
Y-235853D01*
X351378Y-220472D02*
X354541Y-223636D01*
X367442Y-236035D02*
Y-216851D01*
X363672Y-239805D02*
X367442Y-236035D01*
X109519Y-203473D02*
X348548D01*
X108590Y-202173D02*
X349087D01*
X349625Y-200873D02*
X366142Y-217390D01*
X348548Y-203473D02*
X363531Y-218456D01*
X349087Y-202173D02*
X364842Y-217928D01*
X107513Y-199573D02*
X350164D01*
X364842Y-234843D02*
Y-217928D01*
X363531Y-233358D02*
Y-218456D01*
X350164Y-199573D02*
X367442Y-216851D01*
X366142Y-235382D02*
Y-217390D01*
X108052Y-200873D02*
X349625D01*
X100394Y-213366D02*
Y-210370D01*
X98425Y-215551D02*
Y-210500D01*
X97125Y-219488D02*
Y-209961D01*
X107513Y-199573D01*
X98425Y-210500D02*
X108052Y-200873D01*
X100394Y-210370D02*
X108590Y-202173D01*
X102516Y-211571D02*
Y-210476D01*
X109519Y-203473D01*
X102516Y-211571D02*
X102528Y-211583D01*
X86562Y-206411D02*
X106597Y-186376D01*
X85416Y-317699D02*
X92204Y-310911D01*
X89604Y-205207D02*
X106325Y-188487D01*
X93504Y-312439D02*
Y-206823D01*
X86562Y-211183D02*
Y-206411D01*
X89604Y-259805D02*
Y-205207D01*
X92204Y-310911D02*
Y-206284D01*
X86458Y-265779D02*
X90904Y-261334D01*
X93504Y-206823D02*
X107940Y-192387D01*
X85630Y-320313D02*
X93504Y-312439D01*
X92204Y-206284D02*
X107401Y-191087D01*
X90904Y-205746D02*
X106863Y-189787D01*
X85630Y-263779D02*
X89604Y-259805D01*
X90904Y-261334D02*
Y-205746D01*
X107940Y-192387D02*
X407486D01*
X106325Y-188487D02*
X405871D01*
X107401Y-191087D02*
X406948D01*
X106863Y-189787D02*
X406410D01*
X106597Y-186376D02*
X406143D01*
X98425Y-215551D02*
X99410Y-216535D01*
X354852Y-236065D02*
X358592Y-239805D01*
X101378Y-214567D02*
Y-214351D01*
X100394Y-213366D02*
X101378Y-214351D01*
X363019Y-238505D02*
X366142Y-235382D01*
X362480Y-237205D02*
X364842Y-234843D01*
X359692Y-238505D02*
X363019D01*
X357252Y-236065D02*
X359692Y-238505D01*
X357252Y-236065D02*
Y-235853D01*
X356852Y-235453D02*
X357252Y-235853D01*
X356852Y-235453D02*
Y-235236D01*
X85431Y-213583D02*
X85630D01*
X360823Y-237205D02*
X362480D01*
X359652Y-236033D02*
X360823Y-237205D01*
X359252Y-235453D02*
X359652Y-235853D01*
X359252Y-235453D02*
Y-235236D01*
X359652Y-236033D02*
Y-235853D01*
X361652Y-235205D02*
X361684D01*
X363531Y-233358D01*
X85846Y-266179D02*
X86246Y-265779D01*
X85630Y-266179D02*
X85846D01*
X86246Y-265779D02*
X86458D01*
X411043Y-175058D02*
Y-174974D01*
X406143Y-186376D02*
X413286Y-179233D01*
Y-175003D01*
X407486Y-192387D02*
X421596Y-178277D01*
X103691Y-180494D02*
X405607D01*
X89567Y-166370D02*
X103691Y-180494D01*
X413286Y-175003D02*
X413440Y-174850D01*
X405607Y-180494D02*
X411043Y-175058D01*
X405871Y-188487D02*
X415596Y-178762D01*
X406410Y-189787D02*
X417596Y-178600D01*
X406948Y-191087D02*
X419596Y-178439D01*
X84646Y-278543D02*
X87598Y-275590D01*
X83180Y-303391D02*
X84646Y-301924D01*
X83180Y-323337D02*
Y-303391D01*
X84646Y-301924D02*
Y-278543D01*
X83180Y-323337D02*
X84646Y-324803D01*
X97441D01*
X111221Y-311024D01*
Y-220472D01*
X120732Y-210961D02*
X352694D01*
X361531Y-219798D01*
X111221Y-220472D02*
X120732Y-210961D01*
X351378Y-212598D02*
X359131Y-220351D01*
X112536Y-223094D02*
X123031Y-212598D01*
X351378D01*
X361531Y-223425D02*
Y-219798D01*
X81880Y-324990D02*
X83661Y-326772D01*
X100394D02*
X113189Y-313976D01*
X83661Y-326772D02*
X100394D01*
X113189Y-313976D02*
Y-224410D01*
X112536Y-223757D02*
Y-223094D01*
Y-223757D02*
X113189Y-224410D01*
X359131Y-223425D02*
Y-220351D01*
X78740Y-340551D02*
X96457D01*
X118110Y-318898D02*
Y-227362D01*
X96457Y-340551D02*
X118110Y-318898D01*
Y-227362D02*
X125000Y-220472D01*
X351378D01*
X421596Y-178277D02*
Y-175034D01*
X404528Y-158595D02*
Y-156496D01*
X406812Y-154212D02*
X412940D01*
X404528Y-156496D02*
X406812Y-154212D01*
X406528Y-157767D02*
X408782Y-155512D01*
X412402D01*
X404528Y-158595D02*
X405142Y-159209D01*
X405142D01*
X406213Y-160280D02*
X407327D01*
X407480Y-160433D01*
X405142Y-159209D02*
X406213Y-160280D01*
X402559Y-165354D02*
X404528Y-163386D01*
X392434Y-162870D02*
X394794Y-160509D01*
X404604D02*
X407480Y-163386D01*
X394794Y-160509D02*
X404604D01*
X412940Y-154212D02*
X415670Y-156942D01*
X412402Y-155512D02*
X414370Y-157480D01*
X87167Y-166161D02*
X87567Y-165761D01*
X87167Y-166377D02*
Y-166161D01*
X512764Y-104214D02*
X512795D01*
X505905Y-111072D02*
X512764Y-104214D01*
X65945Y-61860D02*
X89173Y-85088D01*
X268898D01*
X290846Y-107037D01*
X65945Y-65797D02*
X86811Y-86663D01*
X268012D02*
X290158Y-108809D01*
X86811Y-86663D02*
X268012D01*
X434252Y-108809D02*
X469291Y-143848D01*
X275098Y-130659D02*
X416634D01*
X272835Y-128395D02*
X275098Y-130659D01*
X437697Y-175246D02*
Y-156939D01*
X475295Y-133612D02*
X477165Y-131742D01*
D239*
X181496Y-120079D02*
D03*
D241*
X270472Y-327165D02*
D03*
X282283D02*
D03*
X142520Y-156693D02*
D03*
X294094Y-327165D02*
D03*
X282283D02*
D03*
X294094D02*
D03*
X142520Y-156693D02*
D03*
X270472Y-327165D02*
D03*
D248*
X539055Y13937D02*
D03*
Y3937D02*
D03*
D250*
X62986Y-112803D02*
D03*
X680709Y-216929D02*
D03*
X671654Y-217323D02*
D03*
X366929Y-75984D02*
D03*
Y-83071D02*
D03*
Y-86614D02*
D03*
Y-89370D02*
D03*
Y-79528D02*
D03*
X679921Y-160236D02*
D03*
X684646Y-161811D02*
D03*
X689370Y-161417D02*
D03*
X689764Y-164567D02*
D03*
Y-168110D02*
D03*
X625000Y-48080D02*
D03*
X476945Y-173228D02*
D03*
X381496Y-127165D02*
D03*
X378740Y-123622D02*
D03*
X377559Y-135433D02*
D03*
X381890Y-137402D02*
D03*
X474016Y-176378D02*
D03*
X530027Y-172987D02*
D03*
X533044Y-176225D02*
D03*
X495669Y-222047D02*
D03*
X500394Y-222835D02*
D03*
X409900Y-136559D02*
D03*
X443307Y-111024D02*
D03*
X255118Y-118504D02*
D03*
X238189Y-116142D02*
D03*
X253690Y-111960D02*
D03*
X271654Y-122835D02*
D03*
X228824Y-104850D02*
D03*
X618898Y-82284D02*
D03*
X620959Y-100047D02*
D03*
X623228Y-93307D02*
D03*
X592520D02*
D03*
X570472Y-137795D02*
D03*
X579921Y-133465D02*
D03*
X574409D02*
D03*
X570866D02*
D03*
X572047Y-129921D02*
D03*
X576378D02*
D03*
X580315D02*
D03*
X678441Y-292586D02*
D03*
X678346Y-297244D02*
D03*
X675197Y-200000D02*
D03*
X678740D02*
D03*
X681890D02*
D03*
Y-196850D02*
D03*
X678740D02*
D03*
X675591Y-196457D02*
D03*
X598425Y-198819D02*
D03*
X595276D02*
D03*
X592126D02*
D03*
X589764D02*
D03*
X587008D02*
D03*
X585039Y-249606D02*
D03*
X590551Y-266535D02*
D03*
X588189Y-263386D02*
D03*
X585433Y-253937D02*
D03*
Y-257480D02*
D03*
X581496D02*
D03*
X577953D02*
D03*
X549213Y-207874D02*
D03*
X544909Y-287437D02*
D03*
X545276Y-275197D02*
D03*
X469685Y-133465D02*
D03*
X498032Y-132283D02*
D03*
X505905Y-123622D02*
D03*
X472441Y-113779D02*
D03*
X483484Y-105840D02*
D03*
X504703Y-106672D02*
D03*
X508268Y-117323D02*
D03*
X101575Y-42126D02*
D03*
X614567Y-44882D02*
D03*
X423461Y-178869D02*
D03*
X120079Y-263386D02*
D03*
X416835Y-196581D02*
D03*
X411811Y-196850D02*
D03*
X570866Y-70472D02*
D03*
Y-72441D02*
D03*
Y-74410D02*
D03*
X574016Y-70472D02*
D03*
Y-72441D02*
D03*
Y-74410D02*
D03*
X379134Y-137795D02*
D03*
X378740Y-127165D02*
D03*
X375532Y-123610D02*
D03*
X375590Y-127165D02*
D03*
X106299Y-263632D02*
D03*
X625000Y-29773D02*
D03*
X544291Y-199655D02*
D03*
X509842Y-197687D02*
D03*
X544291Y-201624D02*
D03*
X509842Y-199655D02*
D03*
Y-201624D02*
D03*
X544291Y-197687D02*
D03*
X509842Y-195718D02*
D03*
X447244Y-324852D02*
D03*
X433858D02*
D03*
X460630D02*
D03*
X431102D02*
D03*
X444488D02*
D03*
X457480D02*
D03*
X222638Y-374655D02*
D03*
X218445Y-374108D02*
D03*
X453937Y-306742D02*
D03*
X451181D02*
D03*
X65945Y-57923D02*
D03*
X615158Y-8858D02*
D03*
X70866Y-122047D02*
D03*
X360204Y-252984D02*
D03*
X417596Y-175197D02*
D03*
X354541Y-223636D02*
D03*
X354452Y-235236D02*
D03*
X356578Y-225247D02*
D03*
X102528Y-211583D02*
D03*
X97125Y-219488D02*
D03*
X99410Y-216535D02*
D03*
X101378Y-214567D02*
D03*
X86614Y-175197D02*
D03*
X361652Y-235205D02*
D03*
X359131Y-223425D02*
D03*
X361531D02*
D03*
X85416Y-317699D02*
D03*
X85630Y-263779D02*
D03*
X86562Y-211183D02*
D03*
X411043Y-174974D02*
D03*
X413440Y-174850D02*
D03*
X421596Y-175034D02*
D03*
X406528Y-157767D02*
D03*
X404528Y-163386D02*
D03*
X407480Y-160433D02*
D03*
X75787Y-232283D02*
D03*
X87167Y-166377D02*
D03*
X89567Y-166370D02*
D03*
X85630Y-213583D02*
D03*
Y-266179D02*
D03*
Y-320313D02*
D03*
X359252Y-235236D02*
D03*
X356852D02*
D03*
X407480Y-163386D02*
D03*
X26575Y19685D02*
D03*
X86614Y-227362D02*
D03*
X63976Y-221457D02*
D03*
Y-275590D02*
D03*
X75787Y-285433D02*
D03*
X87598Y-275590D02*
D03*
Y-281496D02*
D03*
X81880Y-287582D02*
D03*
X62992Y-329724D02*
D03*
X74803Y-339567D02*
D03*
X78740Y-340551D02*
D03*
X87598Y-335630D02*
D03*
Y-329724D02*
D03*
X63976Y-179134D02*
D03*
X74803D02*
D03*
X26575Y-283465D02*
D03*
X30512Y-170276D02*
D03*
X-23622Y-241142D02*
D03*
Y-294291D02*
D03*
Y-346457D02*
D03*
Y-70866D02*
D03*
Y-114173D02*
D03*
Y-187992D02*
D03*
X544291Y-195718D02*
D03*
X533878Y-117716D02*
D03*
X512795Y-104214D02*
D03*
X430807Y-175344D02*
D03*
X210433Y-374655D02*
D03*
X206496D02*
D03*
X442126Y-306742D02*
D03*
X439370D02*
D03*
X237992Y-374655D02*
D03*
X241929D02*
D03*
X253655Y-374421D02*
D03*
X256890Y-374655D02*
D03*
X273425D02*
D03*
X269502Y-374291D02*
D03*
X269685Y-106151D02*
D03*
X131890Y-72687D02*
D03*
X443898Y-175049D02*
D03*
X65945Y-65797D02*
D03*
X78740Y-238041D02*
D03*
X33465Y19833D02*
D03*
X40354Y19685D02*
D03*
X47244D02*
D03*
X469291Y-143848D02*
D03*
X469390Y-175147D02*
D03*
X437697Y-175246D02*
D03*
X433858D02*
D03*
M02*
